(kicad_sch
	(version 20250114)
	(generator "eeschema")
	(generator_version "9.0")
	(paper "A3")
	(title_block
		(title "COM Express 7 Baseboard")
		(date "2025-02-04")
		(rev "1.1.2")
		(company "Antmicro Ltd")
		(comment 1 "www.antmicro.com")
	)
	(bus_alias "SPI"
		(members "MISO" "MOSI" "CLK" "~{CS}")
	)
	(text "Carrier Board EEPROM"
		(exclude_from_sim no)
		(at 222.25 176.53 0)
		(effects
			(font
				(size 2 2)
				(thickness 0.4)
				(bold yes)
			)
			(justify left bottom)
		)
	)
	(text "Assert PSON when:\nPush button controller outputs 1\nCOM7 module detected"
		(exclude_from_sim no)
		(at 343.535 68.58 0)
		(effects
			(font
				(size 1.27 1.27)
			)
			(justify left bottom)
		)
	)
	(text "COM Express 7 power and management"
		(exclude_from_sim no)
		(at 67.31 22.86 0)
		(effects
			(font
				(size 2 2)
				(thickness 0.4)
				(bold yes)
			)
			(justify left bottom)
		)
	)
	(text "Carrier MAFS BIOS"
		(exclude_from_sim no)
		(at 335.28 175.26 0)
		(effects
			(font
				(size 2 2)
				(thickness 0.4)
				(bold yes)
			)
			(justify left bottom)
		)
	)
	(text "Clear CMOS\njumper"
		(exclude_from_sim no)
		(at 110.49 58.42 0)
		(effects
			(font
				(size 1.27 1.27)
			)
			(justify left bottom)
		)
	)
	(text "Simulate button\nclick for autostart"
		(exclude_from_sim no)
		(at 236.855 115.57 0)
		(effects
			(font
				(size 1.27 1.27)
			)
			(justify left bottom)
		)
	)
	(text "Carrier MAFS\nBIOS"
		(exclude_from_sim no)
		(at 363.22 226.06 0)
		(effects
			(font
				(size 1.27 1.27)
			)
			(justify left bottom)
		)
	)
	(text "Power and reset"
		(exclude_from_sim no)
		(at 275.59 26.67 0)
		(effects
			(font
				(size 2 2)
				(thickness 0.4)
				(bold yes)
			)
			(justify left bottom)
		)
	)
	(text "Check if module is type 7:\n~{TYPE0} GND\n~{TYPE1} NC\n~{TYPE2} GND"
		(exclude_from_sim no)
		(at 247.65 162.56 0)
		(effects
			(font
				(size 1.27 1.27)
			)
			(justify left bottom)
		)
	)
	(text "Defines Master Attached \nFlash Sharing location\nClosed for MAFS on Module\nOpen for MAFS on Carrier"
		(exclude_from_sim no)
		(at 325.12 246.38 0)
		(effects
			(font
				(size 1.27 1.27)
			)
			(justify left bottom)
		)
	)
	(text "Power button"
		(exclude_from_sim no)
		(at 219.71 75.565 0)
		(effects
			(font
				(size 1.27 1.27)
				(thickness 0.254)
				(bold yes)
			)
			(justify left bottom)
		)
	)
	(text "Remove to disable\nautostartup"
		(exclude_from_sim no)
		(at 274.955 89.535 0)
		(effects
			(font
				(size 1.27 1.27)
			)
			(justify left bottom)
		)
	)
	(text "Shutdown power \nwhen S5 asserted"
		(exclude_from_sim no)
		(at 246.38 63.5 0)
		(effects
			(font
				(size 1.27 1.27)
			)
			(justify left bottom)
		)
	)
	(text "Devices on the I2C bus:\n* 0x2D ADT7476AARQZ\n* 0x40 12V Current/Power Monitor\n* 0x41 3V3 Current/Power Monitor\n* 0x42 5V0 Current/Power Monitor \n* 0x50, \n  0x58 Module EEPROM \n* 0x57,\n  0x5F Board EEPROM\n"
		(exclude_from_sim no)
		(at 110.49 281.94 0)
		(effects
			(font
				(size 1.27 1.27)
			)
			(justify left bottom)
		)
	)
	(junction
		(at 292.1 143.51)
		(diameter 0)
		(color 0 0 0 0)
	)
	(junction
		(at 278.13 52.07)
		(diameter 0)
		(color 0 0 0 0)
	)
	(junction
		(at 113.03 139.7)
		(diameter 0)
		(color 0 0 0 0)
	)
	(junction
		(at 218.44 85.09)
		(diameter 0)
		(color 0 0 0 0)
	)
	(junction
		(at 138.43 58.42)
		(diameter 0)
		(color 0 0 0 0)
	)
	(junction
		(at 264.16 83.82)
		(diameter 0)
		(color 0 0 0 0)
	)
	(junction
		(at 91.44 184.15)
		(diameter 0)
		(color 0 0 0 0)
	)
	(junction
		(at 356.87 193.04)
		(diameter 0)
		(color 0 0 0 0)
	)
	(junction
		(at 93.98 38.1)
		(diameter 0)
		(color 0 0 0 0)
	)
	(junction
		(at 91.44 193.04)
		(diameter 0)
		(color 0 0 0 0)
	)
	(junction
		(at 228.6 218.44)
		(diameter 0)
		(color 0 0 0 0)
	)
	(junction
		(at 264.16 71.12)
		(diameter 0)
		(color 0 0 0 0)
	)
	(junction
		(at 256.54 132.08)
		(diameter 0)
		(color 0 0 0 0)
	)
	(junction
		(at 284.48 143.51)
		(diameter 0)
		(color 0 0 0 0)
	)
	(junction
		(at 248.92 140.97)
		(diameter 0)
		(color 0 0 0 0)
	)
	(junction
		(at 78.74 50.8)
		(diameter 0)
		(color 0 0 0 0)
	)
	(junction
		(at 259.08 209.55)
		(diameter 0)
		(color 0 0 0 0)
	)
	(junction
		(at 91.44 68.58)
		(diameter 0)
		(color 0 0 0 0)
	)
	(junction
		(at 285.75 128.27)
		(diameter 0)
		(color 0 0 0 0)
	)
	(junction
		(at 120.65 144.78)
		(diameter 0)
		(color 0 0 0 0)
	)
	(junction
		(at 116.84 60.96)
		(diameter 0)
		(color 0 0 0 0)
	)
	(junction
		(at 228.6 220.98)
		(diameter 0)
		(color 0 0 0 0)
	)
	(junction
		(at 250.19 217.17)
		(diameter 0)
		(color 0 0 0 0)
	)
	(junction
		(at 78.74 81.28)
		(diameter 0)
		(color 0 0 0 0)
	)
	(junction
		(at 250.19 224.79)
		(diameter 0)
		(color 0 0 0 0)
	)
	(junction
		(at 104.14 38.1)
		(diameter 0)
		(color 0 0 0 0)
	)
	(junction
		(at 264.16 73.66)
		(diameter 0)
		(color 0 0 0 0)
	)
	(junction
		(at 382.27 193.04)
		(diameter 0)
		(color 0 0 0 0)
	)
	(junction
		(at 78.74 53.34)
		(diameter 0)
		(color 0 0 0 0)
	)
	(junction
		(at 218.44 71.12)
		(diameter 0)
		(color 0 0 0 0)
	)
	(junction
		(at 228.6 71.12)
		(diameter 0)
		(color 0 0 0 0)
	)
	(junction
		(at 331.47 60.96)
		(diameter 0)
		(color 0 0 0 0)
	)
	(junction
		(at 106.68 71.12)
		(diameter 0)
		(color 0 0 0 0)
	)
	(junction
		(at 82.55 38.1)
		(diameter 0)
		(color 0 0 0 0)
	)
	(junction
		(at 349.25 193.04)
		(diameter 0)
		(color 0 0 0 0)
	)
	(junction
		(at 302.26 60.96)
		(diameter 0)
		(color 0 0 0 0)
	)
	(junction
		(at 248.92 132.08)
		(diameter 0)
		(color 0 0 0 0)
	)
	(junction
		(at 121.92 139.7)
		(diameter 0)
		(color 0 0 0 0)
	)
	(junction
		(at 218.44 102.87)
		(diameter 0)
		(color 0 0 0 0)
	)
	(junction
		(at 250.19 209.55)
		(diameter 0)
		(color 0 0 0 0)
	)
	(junction
		(at 264.16 146.05)
		(diameter 0)
		(color 0 0 0 0)
	)
	(junction
		(at 99.06 195.58)
		(diameter 0)
		(color 0 0 0 0)
	)
	(junction
		(at 256.54 143.51)
		(diameter 0)
		(color 0 0 0 0)
	)
	(junction
		(at 231.14 53.34)
		(diameter 0)
		(color 0 0 0 0)
	)
	(junction
		(at 116.84 121.92)
		(diameter 0)
		(color 0 0 0 0)
	)
	(junction
		(at 264.16 44.45)
		(diameter 0)
		(color 0 0 0 0)
	)
	(junction
		(at 270.51 68.58)
		(diameter 0)
		(color 0 0 0 0)
	)
	(junction
		(at 337.82 60.96)
		(diameter 0)
		(color 0 0 0 0)
	)
	(junction
		(at 382.27 205.74)
		(diameter 0)
		(color 0 0 0 0)
	)
	(junction
		(at 233.68 71.12)
		(diameter 0)
		(color 0 0 0 0)
	)
	(no_connect
		(at 76.2 152.4)
	)
	(no_connect
		(at 363.22 237.49)
	)
	(no_connect
		(at 254 85.09)
	)
	(no_connect
		(at 76.2 177.8)
	)
	(no_connect
		(at 323.85 195.58)
	)
	(no_connect
		(at 76.2 149.86)
	)
	(no_connect
		(at 76.2 175.26)
	)
	(no_connect
		(at 190.5 96.52)
	)
	(bus_entry
		(at 212.09 213.36)
		(size 1.27 1.27)
		(stroke
			(width 0)
			(type default)
		)
	)
	(bus_entry
		(at 92.71 160.02)
		(size 1.27 -1.27)
		(stroke
			(width 0)
			(type default)
		)
	)
	(bus_entry
		(at 93.98 267.97)
		(size -1.27 1.27)
		(stroke
			(width 0)
			(type default)
		)
	)
	(bus_entry
		(at 92.71 254)
		(size 1.27 -1.27)
		(stroke
			(width 0)
			(type default)
		)
	)
	(bus_entry
		(at 327.66 208.28)
		(size -1.27 -1.27)
		(stroke
			(width 0)
			(type default)
		)
	)
	(bus_entry
		(at 327.66 213.36)
		(size -1.27 -1.27)
		(stroke
			(width 0)
			(type default)
		)
	)
	(bus_entry
		(at 92.71 241.3)
		(size 1.27 -1.27)
		(stroke
			(width 0)
			(type default)
		)
	)
	(bus_entry
		(at 93.98 270.51)
		(size -1.27 1.27)
		(stroke
			(width 0)
			(type default)
		)
	)
	(bus_entry
		(at 92.71 248.92)
		(size 1.27 -1.27)
		(stroke
			(width 0)
			(type default)
		)
	)
	(bus_entry
		(at 92.71 243.84)
		(size 1.27 -1.27)
		(stroke
			(width 0)
			(type default)
		)
	)
	(bus_entry
		(at 327.66 210.82)
		(size -1.27 -1.27)
		(stroke
			(width 0)
			(type default)
		)
	)
	(bus_entry
		(at 92.71 157.48)
		(size 1.27 -1.27)
		(stroke
			(width 0)
			(type default)
		)
	)
	(bus_entry
		(at 92.71 154.94)
		(size 1.27 -1.27)
		(stroke
			(width 0)
			(type default)
		)
	)
	(bus_entry
		(at 327.66 205.74)
		(size -1.27 -1.27)
		(stroke
			(width 0)
			(type default)
		)
	)
	(bus_entry
		(at 92.71 264.16)
		(size 1.27 -1.27)
		(stroke
			(width 0)
			(type default)
		)
	)
	(bus_entry
		(at 212.09 210.82)
		(size 1.27 1.27)
		(stroke
			(width 0)
			(type default)
		)
	)
	(bus_entry
		(at 92.71 246.38)
		(size 1.27 -1.27)
		(stroke
			(width 0)
			(type default)
		)
	)
	(bus_entry
		(at 92.71 261.62)
		(size 1.27 -1.27)
		(stroke
			(width 0)
			(type default)
		)
	)
	(bus_entry
		(at 92.71 256.54)
		(size 1.27 -1.27)
		(stroke
			(width 0)
			(type default)
		)
	)
	(wire
		(pts
			(xy 349.25 193.04) (xy 349.25 195.58)
		)
		(stroke
			(width 0)
			(type default)
		)
	)
	(bus
		(pts
			(xy 93.98 152.4) (xy 93.98 153.67)
		)
		(stroke
			(width 0)
			(type default)
		)
	)
	(wire
		(pts
			(xy 331.47 60.96) (xy 331.47 139.7)
		)
		(stroke
			(width 0)
			(type default)
		)
	)
	(wire
		(pts
			(xy 104.14 38.1) (xy 104.14 40.64)
		)
		(stroke
			(width 0)
			(type default)
		)
	)
	(bus
		(pts
			(xy 96.52 266.7) (xy 95.25 266.7)
		)
		(stroke
			(width 0)
			(type default)
		)
	)
	(wire
		(pts
			(xy 97.79 132.08) (xy 76.2 132.08)
		)
		(stroke
			(width 0)
			(type default)
		)
	)
	(wire
		(pts
			(xy 104.14 45.72) (xy 104.14 46.99)
		)
		(stroke
			(width 0)
			(type default)
		)
	)
	(wire
		(pts
			(xy 76.2 147.32) (xy 88.9 147.32)
		)
		(stroke
			(width 0)
			(type default)
		)
	)
	(wire
		(pts
			(xy 289.56 138.43) (xy 289.56 148.59)
		)
		(stroke
			(width 0)
			(type default)
		)
	)
	(wire
		(pts
			(xy 186.69 104.14) (xy 186.69 101.6)
		)
		(stroke
			(width 0)
			(type default)
		)
	)
	(wire
		(pts
			(xy 250.19 217.17) (xy 245.11 217.17)
		)
		(stroke
			(width 0)
			(type default)
		)
	)
	(wire
		(pts
			(xy 259.08 83.82) (xy 259.08 81.28)
		)
		(stroke
			(width 0)
			(type default)
		)
	)
	(wire
		(pts
			(xy 142.24 139.7) (xy 140.97 139.7)
		)
		(stroke
			(width 0)
			(type default)
		)
	)
	(wire
		(pts
			(xy 88.9 60.96) (xy 88.9 59.69)
		)
		(stroke
			(width 0)
			(type default)
		)
	)
	(wire
		(pts
			(xy 113.03 139.7) (xy 113.03 140.97)
		)
		(stroke
			(width 0)
			(type default)
		)
	)
	(wire
		(pts
			(xy 82.55 66.04) (xy 82.55 38.1)
		)
		(stroke
			(width 0)
			(type default)
		)
	)
	(wire
		(pts
			(xy 76.2 68.58) (xy 91.44 68.58)
		)
		(stroke
			(width 0)
			(type default)
		)
	)
	(wire
		(pts
			(xy 259.08 83.82) (xy 264.16 83.82)
		)
		(stroke
			(width 0)
			(type default)
		)
	)
	(wire
		(pts
			(xy 76.2 271.78) (xy 92.71 271.78)
		)
		(stroke
			(width 0)
			(type default)
		)
	)
	(wire
		(pts
			(xy 218.44 85.09) (xy 218.44 86.36)
		)
		(stroke
			(width 0)
			(type default)
		)
	)
	(wire
		(pts
			(xy 218.44 71.12) (xy 228.6 71.12)
		)
		(stroke
			(width 0)
			(type default)
		)
	)
	(bus
		(pts
			(xy 93.98 240.03) (xy 95.25 238.76)
		)
		(stroke
			(width 0)
			(type default)
		)
	)
	(wire
		(pts
			(xy 83.82 218.44) (xy 76.2 218.44)
		)
		(stroke
			(width 0)
			(type default)
		)
	)
	(wire
		(pts
			(xy 264.16 81.28) (xy 264.16 83.82)
		)
		(stroke
			(width 0)
			(type default)
		)
	)
	(wire
		(pts
			(xy 281.94 143.51) (xy 284.48 143.51)
		)
		(stroke
			(width 0)
			(type default)
		)
	)
	(bus
		(pts
			(xy 95.25 251.46) (xy 96.52 251.46)
		)
		(stroke
			(width 0)
			(type default)
		)
	)
	(wire
		(pts
			(xy 106.68 68.58) (xy 106.68 71.12)
		)
		(stroke
			(width 0)
			(type default)
		)
	)
	(wire
		(pts
			(xy 270.51 52.07) (xy 278.13 52.07)
		)
		(stroke
			(width 0)
			(type default)
		)
	)
	(wire
		(pts
			(xy 293.37 158.75) (xy 293.37 153.67)
		)
		(stroke
			(width 0)
			(type default)
		)
	)
	(wire
		(pts
			(xy 218.44 71.12) (xy 218.44 73.66)
		)
		(stroke
			(width 0)
			(type default)
		)
	)
	(wire
		(pts
			(xy 92.71 157.48) (xy 76.2 157.48)
		)
		(stroke
			(width 0)
			(type default)
		)
	)
	(wire
		(pts
			(xy 121.92 121.92) (xy 116.84 121.92)
		)
		(stroke
			(width 0)
			(type default)
		)
	)
	(wire
		(pts
			(xy 218.44 53.34) (xy 231.14 53.34)
		)
		(stroke
			(width 0)
			(type default)
		)
	)
	(wire
		(pts
			(xy 264.16 87.63) (xy 254 87.63)
		)
		(stroke
			(width 0)
			(type default)
		)
	)
	(wire
		(pts
			(xy 228.6 218.44) (xy 228.6 220.98)
		)
		(stroke
			(width 0)
			(type default)
		)
	)
	(bus
		(pts
			(xy 93.98 262.89) (xy 93.98 260.35)
		)
		(stroke
			(width 0)
			(type default)
		)
	)
	(wire
		(pts
			(xy 256.54 138.43) (xy 256.54 143.51)
		)
		(stroke
			(width 0)
			(type default)
		)
	)
	(wire
		(pts
			(xy 299.72 68.58) (xy 307.34 68.58)
		)
		(stroke
			(width 0)
			(type default)
		)
	)
	(wire
		(pts
			(xy 245.11 212.09) (xy 247.65 212.09)
		)
		(stroke
			(width 0)
			(type default)
		)
	)
	(wire
		(pts
			(xy 247.65 212.09) (xy 247.65 209.55)
		)
		(stroke
			(width 0)
			(type default)
		)
	)
	(wire
		(pts
			(xy 233.68 143.51) (xy 256.54 143.51)
		)
		(stroke
			(width 0)
			(type default)
		)
	)
	(bus
		(pts
			(xy 326.39 204.47) (xy 325.12 203.2)
		)
		(stroke
			(width 0)
			(type default)
		)
	)
	(wire
		(pts
			(xy 121.92 121.92) (xy 121.92 137.16)
		)
		(stroke
			(width 0)
			(type default)
		)
	)
	(wire
		(pts
			(xy 121.92 139.7) (xy 113.03 139.7)
		)
		(stroke
			(width 0)
			(type default)
		)
	)
	(wire
		(pts
			(xy 121.92 149.86) (xy 121.92 151.13)
		)
		(stroke
			(width 0)
			(type default)
		)
	)
	(wire
		(pts
			(xy 147.32 144.78) (xy 140.97 144.78)
		)
		(stroke
			(width 0)
			(type default)
		)
	)
	(wire
		(pts
			(xy 356.87 210.82) (xy 360.68 210.82)
		)
		(stroke
			(width 0)
			(type default)
		)
	)
	(wire
		(pts
			(xy 186.69 101.6) (xy 190.5 101.6)
		)
		(stroke
			(width 0)
			(type default)
		)
	)
	(wire
		(pts
			(xy 83.82 215.9) (xy 76.2 215.9)
		)
		(stroke
			(width 0)
			(type default)
		)
	)
	(wire
		(pts
			(xy 381 218.44) (xy 381 219.71)
		)
		(stroke
			(width 0)
			(type default)
		)
	)
	(wire
		(pts
			(xy 294.64 140.97) (xy 293.37 140.97)
		)
		(stroke
			(width 0)
			(type default)
		)
	)
	(wire
		(pts
			(xy 106.68 83.82) (xy 106.68 78.74)
		)
		(stroke
			(width 0)
			(type default)
		)
	)
	(wire
		(pts
			(xy 248.92 132.08) (xy 248.92 133.35)
		)
		(stroke
			(width 0)
			(type default)
		)
	)
	(bus
		(pts
			(xy 95.25 238.76) (xy 102.87 238.76)
		)
		(stroke
			(width 0)
			(type default)
		)
	)
	(wire
		(pts
			(xy 91.44 184.15) (xy 91.44 185.42)
		)
		(stroke
			(width 0)
			(type default)
		)
	)
	(wire
		(pts
			(xy 250.19 224.79) (xy 250.19 226.06)
		)
		(stroke
			(width 0)
			(type default)
		)
	)
	(wire
		(pts
			(xy 264.16 90.17) (xy 264.16 93.98)
		)
		(stroke
			(width 0)
			(type default)
		)
	)
	(wire
		(pts
			(xy 76.2 50.8) (xy 78.74 50.8)
		)
		(stroke
			(width 0)
			(type default)
		)
	)
	(wire
		(pts
			(xy 337.82 60.96) (xy 337.82 71.12)
		)
		(stroke
			(width 0)
			(type default)
		)
	)
	(wire
		(pts
			(xy 360.68 240.03) (xy 363.22 240.03)
		)
		(stroke
			(width 0)
			(type default)
		)
	)
	(wire
		(pts
			(xy 294.64 146.05) (xy 292.1 146.05)
		)
		(stroke
			(width 0)
			(type default)
		)
	)
	(wire
		(pts
			(xy 248.92 130.81) (xy 248.92 132.08)
		)
		(stroke
			(width 0)
			(type default)
		)
	)
	(wire
		(pts
			(xy 256.54 102.87) (xy 254 102.87)
		)
		(stroke
			(width 0)
			(type default)
		)
	)
	(wire
		(pts
			(xy 120.65 134.62) (xy 142.24 134.62)
		)
		(stroke
			(width 0)
			(type default)
		)
	)
	(wire
		(pts
			(xy 76.2 261.62) (xy 92.71 261.62)
		)
		(stroke
			(width 0)
			(type default)
		)
	)
	(wire
		(pts
			(xy 331.47 60.96) (xy 337.82 60.96)
		)
		(stroke
			(width 0)
			(type default)
		)
	)
	(wire
		(pts
			(xy 180.34 99.06) (xy 190.5 99.06)
		)
		(stroke
			(width 0)
			(type default)
		)
	)
	(wire
		(pts
			(xy 349.25 213.36) (xy 360.68 213.36)
		)
		(stroke
			(width 0)
			(type default)
		)
	)
	(wire
		(pts
			(xy 91.44 182.88) (xy 91.44 184.15)
		)
		(stroke
			(width 0)
			(type default)
		)
	)
	(wire
		(pts
			(xy 93.98 45.72) (xy 93.98 46.99)
		)
		(stroke
			(width 0)
			(type default)
		)
	)
	(wire
		(pts
			(xy 311.15 190.5) (xy 323.85 190.5)
		)
		(stroke
			(width 0)
			(type default)
		)
	)
	(wire
		(pts
			(xy 76.2 243.84) (xy 92.71 243.84)
		)
		(stroke
			(width 0)
			(type default)
		)
	)
	(wire
		(pts
			(xy 78.74 53.34) (xy 78.74 55.88)
		)
		(stroke
			(width 0)
			(type default)
		)
	)
	(wire
		(pts
			(xy 264.16 83.82) (xy 264.16 87.63)
		)
		(stroke
			(width 0)
			(type default)
		)
	)
	(wire
		(pts
			(xy 228.6 71.12) (xy 233.68 71.12)
		)
		(stroke
			(width 0)
			(type default)
		)
	)
	(wire
		(pts
			(xy 256.54 151.13) (xy 294.64 151.13)
		)
		(stroke
			(width 0)
			(type default)
		)
	)
	(wire
		(pts
			(xy 76.2 48.26) (xy 78.74 48.26)
		)
		(stroke
			(width 0)
			(type default)
		)
	)
	(wire
		(pts
			(xy 229.87 223.52) (xy 228.6 223.52)
		)
		(stroke
			(width 0)
			(type default)
		)
	)
	(wire
		(pts
			(xy 292.1 143.51) (xy 294.64 143.51)
		)
		(stroke
			(width 0)
			(type default)
		)
	)
	(wire
		(pts
			(xy 123.19 137.16) (xy 121.92 137.16)
		)
		(stroke
			(width 0)
			(type default)
		)
	)
	(wire
		(pts
			(xy 120.65 144.78) (xy 120.65 134.62)
		)
		(stroke
			(width 0)
			(type default)
		)
	)
	(wire
		(pts
			(xy 264.16 90.17) (xy 254 90.17)
		)
		(stroke
			(width 0)
			(type default)
		)
	)
	(bus
		(pts
			(xy 97.79 151.13) (xy 95.25 151.13)
		)
		(stroke
			(width 0)
			(type default)
		)
	)
	(wire
		(pts
			(xy 135.89 63.5) (xy 138.43 63.5)
		)
		(stroke
			(width 0)
			(type default)
		)
	)
	(wire
		(pts
			(xy 231.14 50.8) (xy 231.14 53.34)
		)
		(stroke
			(width 0)
			(type default)
		)
	)
	(wire
		(pts
			(xy 218.44 83.82) (xy 218.44 85.09)
		)
		(stroke
			(width 0)
			(type default)
		)
	)
	(wire
		(pts
			(xy 293.37 128.27) (xy 285.75 128.27)
		)
		(stroke
			(width 0)
			(type default)
		)
	)
	(wire
		(pts
			(xy 256.54 107.95) (xy 254 107.95)
		)
		(stroke
			(width 0)
			(type default)
		)
	)
	(wire
		(pts
			(xy 99.06 184.15) (xy 99.06 185.42)
		)
		(stroke
			(width 0)
			(type default)
		)
	)
	(wire
		(pts
			(xy 76.2 134.62) (xy 88.9 134.62)
		)
		(stroke
			(width 0)
			(type default)
		)
	)
	(wire
		(pts
			(xy 284.48 143.51) (xy 292.1 143.51)
		)
		(stroke
			(width 0)
			(type default)
		)
	)
	(wire
		(pts
			(xy 233.68 68.58) (xy 233.68 71.12)
		)
		(stroke
			(width 0)
			(type default)
		)
	)
	(polyline
		(pts
			(xy 177.8 170.18) (xy 406.4 170.18)
		)
		(stroke
			(width 0)
			(type dash)
		)
	)
	(wire
		(pts
			(xy 248.92 132.08) (xy 256.54 132.08)
		)
		(stroke
			(width 0)
			(type default)
		)
	)
	(wire
		(pts
			(xy 363.22 242.57) (xy 360.68 242.57)
		)
		(stroke
			(width 0)
			(type default)
		)
	)
	(wire
		(pts
			(xy 293.37 140.97) (xy 293.37 128.27)
		)
		(stroke
			(width 0)
			(type default)
		)
	)
	(wire
		(pts
			(xy 123.19 144.78) (xy 120.65 144.78)
		)
		(stroke
			(width 0)
			(type default)
		)
	)
	(wire
		(pts
			(xy 93.98 59.69) (xy 93.98 60.96)
		)
		(stroke
			(width 0)
			(type default)
		)
	)
	(wire
		(pts
			(xy 248.92 140.97) (xy 248.92 138.43)
		)
		(stroke
			(width 0)
			(type default)
		)
	)
	(wire
		(pts
			(xy 302.26 73.66) (xy 299.72 73.66)
		)
		(stroke
			(width 0)
			(type default)
		)
	)
	(wire
		(pts
			(xy 228.6 68.58) (xy 228.6 71.12)
		)
		(stroke
			(width 0)
			(type default)
		)
	)
	(polyline
		(pts
			(xy 299.72 170.18) (xy 299.72 254)
		)
		(stroke
			(width 0)
			(type dash)
		)
	)
	(bus
		(pts
			(xy 93.98 260.35) (xy 95.25 259.08)
		)
		(stroke
			(width 0)
			(type default)
		)
	)
	(wire
		(pts
			(xy 123.19 149.86) (xy 121.92 149.86)
		)
		(stroke
			(width 0)
			(type default)
		)
	)
	(wire
		(pts
			(xy 264.16 106.68) (xy 264.16 118.11)
		)
		(stroke
			(width 0)
			(type default)
		)
	)
	(wire
		(pts
			(xy 345.44 215.9) (xy 360.68 215.9)
		)
		(stroke
			(width 0)
			(type default)
		)
	)
	(wire
		(pts
			(xy 76.2 254) (xy 92.71 254)
		)
		(stroke
			(width 0)
			(type default)
		)
	)
	(wire
		(pts
			(xy 264.16 44.45) (xy 264.16 41.91)
		)
		(stroke
			(width 0)
			(type default)
		)
	)
	(wire
		(pts
			(xy 116.84 68.58) (xy 116.84 71.12)
		)
		(stroke
			(width 0)
			(type default)
		)
	)
	(wire
		(pts
			(xy 116.84 83.82) (xy 116.84 80.01)
		)
		(stroke
			(width 0)
			(type default)
		)
	)
	(wire
		(pts
			(xy 233.68 146.05) (xy 264.16 146.05)
		)
		(stroke
			(width 0)
			(type default)
		)
	)
	(wire
		(pts
			(xy 76.2 241.3) (xy 92.71 241.3)
		)
		(stroke
			(width 0)
			(type default)
		)
	)
	(wire
		(pts
			(xy 76.2 139.7) (xy 113.03 139.7)
		)
		(stroke
			(width 0)
			(type default)
		)
	)
	(wire
		(pts
			(xy 307.34 76.2) (xy 307.34 78.74)
		)
		(stroke
			(width 0)
			(type default)
		)
	)
	(wire
		(pts
			(xy 356.87 193.04) (xy 356.87 195.58)
		)
		(stroke
			(width 0)
			(type default)
		)
	)
	(wire
		(pts
			(xy 299.72 60.96) (xy 302.26 60.96)
		)
		(stroke
			(width 0)
			(type default)
		)
	)
	(wire
		(pts
			(xy 106.68 71.12) (xy 106.68 73.66)
		)
		(stroke
			(width 0)
			(type default)
		)
	)
	(wire
		(pts
			(xy 302.26 50.8) (xy 302.26 53.34)
		)
		(stroke
			(width 0)
			(type default)
		)
	)
	(bus
		(pts
			(xy 326.39 207.01) (xy 326.39 209.55)
		)
		(stroke
			(width 0)
			(type default)
		)
	)
	(wire
		(pts
			(xy 78.74 48.26) (xy 78.74 50.8)
		)
		(stroke
			(width 0)
			(type default)
		)
	)
	(wire
		(pts
			(xy 327.66 208.28) (xy 360.68 208.28)
		)
		(stroke
			(width 0)
			(type default)
		)
	)
	(wire
		(pts
			(xy 256.54 107.95) (xy 256.54 118.11)
		)
		(stroke
			(width 0)
			(type default)
		)
	)
	(wire
		(pts
			(xy 142.24 134.62) (xy 142.24 139.7)
		)
		(stroke
			(width 0)
			(type default)
		)
	)
	(wire
		(pts
			(xy 335.28 231.14) (xy 350.52 231.14)
		)
		(stroke
			(width 0)
			(type default)
		)
	)
	(wire
		(pts
			(xy 278.13 52.07) (xy 278.13 60.96)
		)
		(stroke
			(width 0)
			(type default)
		)
	)
	(wire
		(pts
			(xy 356.87 200.66) (xy 356.87 210.82)
		)
		(stroke
			(width 0)
			(type default)
		)
	)
	(wire
		(pts
			(xy 256.54 132.08) (xy 264.16 132.08)
		)
		(stroke
			(width 0)
			(type default)
		)
	)
	(wire
		(pts
			(xy 218.44 102.87) (xy 236.22 102.87)
		)
		(stroke
			(width 0)
			(type default)
		)
	)
	(wire
		(pts
			(xy 215.9 83.82) (xy 215.9 85.09)
		)
		(stroke
			(width 0)
			(type default)
		)
	)
	(wire
		(pts
			(xy 360.68 231.14) (xy 360.68 240.03)
		)
		(stroke
			(width 0)
			(type default)
		)
	)
	(wire
		(pts
			(xy 91.44 184.15) (xy 99.06 184.15)
		)
		(stroke
			(width 0)
			(type default)
		)
	)
	(wire
		(pts
			(xy 231.14 53.34) (xy 231.14 55.88)
		)
		(stroke
			(width 0)
			(type default)
		)
	)
	(wire
		(pts
			(xy 312.42 143.51) (xy 314.96 143.51)
		)
		(stroke
			(width 0)
			(type default)
		)
	)
	(wire
		(pts
			(xy 250.19 215.9) (xy 250.19 217.17)
		)
		(stroke
			(width 0)
			(type default)
		)
	)
	(wire
		(pts
			(xy 233.68 71.12) (xy 264.16 71.12)
		)
		(stroke
			(width 0)
			(type default)
		)
	)
	(wire
		(pts
			(xy 284.48 143.51) (xy 284.48 153.67)
		)
		(stroke
			(width 0)
			(type default)
		)
	)
	(wire
		(pts
			(xy 293.37 153.67) (xy 294.64 153.67)
		)
		(stroke
			(width 0)
			(type default)
		)
	)
	(wire
		(pts
			(xy 92.71 154.94) (xy 76.2 154.94)
		)
		(stroke
			(width 0)
			(type default)
		)
	)
	(wire
		(pts
			(xy 356.87 193.04) (xy 382.27 193.04)
		)
		(stroke
			(width 0)
			(type default)
		)
	)
	(wire
		(pts
			(xy 120.65 144.78) (xy 120.65 147.32)
		)
		(stroke
			(width 0)
			(type default)
		)
	)
	(bus
		(pts
			(xy 93.98 242.57) (xy 93.98 245.11)
		)
		(stroke
			(width 0)
			(type default)
		)
	)
	(wire
		(pts
			(xy 228.6 118.11) (xy 228.6 115.57)
		)
		(stroke
			(width 0)
			(type default)
		)
	)
	(wire
		(pts
			(xy 336.55 193.04) (xy 349.25 193.04)
		)
		(stroke
			(width 0)
			(type default)
		)
	)
	(bus
		(pts
			(xy 212.09 210.82) (xy 212.09 213.36)
		)
		(stroke
			(width 0)
			(type default)
		)
	)
	(wire
		(pts
			(xy 95.25 134.62) (xy 95.25 135.89)
		)
		(stroke
			(width 0)
			(type default)
		)
	)
	(wire
		(pts
			(xy 99.06 195.58) (xy 104.14 195.58)
		)
		(stroke
			(width 0)
			(type default)
		)
	)
	(bus
		(pts
			(xy 210.82 209.55) (xy 201.93 209.55)
		)
		(stroke
			(width 0)
			(type default)
		)
	)
	(wire
		(pts
			(xy 82.55 38.1) (xy 76.2 38.1)
		)
		(stroke
			(width 0)
			(type default)
		)
	)
	(wire
		(pts
			(xy 116.84 60.96) (xy 123.19 60.96)
		)
		(stroke
			(width 0)
			(type default)
		)
	)
	(wire
		(pts
			(xy 248.92 140.97) (xy 269.24 140.97)
		)
		(stroke
			(width 0)
			(type default)
		)
	)
	(wire
		(pts
			(xy 76.2 81.28) (xy 78.74 81.28)
		)
		(stroke
			(width 0)
			(type default)
		)
	)
	(wire
		(pts
			(xy 327.66 210.82) (xy 345.44 210.82)
		)
		(stroke
			(width 0)
			(type default)
		)
	)
	(wire
		(pts
			(xy 247.65 223.52) (xy 245.11 223.52)
		)
		(stroke
			(width 0)
			(type default)
		)
	)
	(bus
		(pts
			(xy 93.98 153.67) (xy 93.98 156.21)
		)
		(stroke
			(width 0)
			(type default)
		)
	)
	(wire
		(pts
			(xy 91.44 59.69) (xy 91.44 68.58)
		)
		(stroke
			(width 0)
			(type default)
		)
	)
	(wire
		(pts
			(xy 246.38 68.58) (xy 260.35 68.58)
		)
		(stroke
			(width 0)
			(type default)
		)
	)
	(wire
		(pts
			(xy 247.65 209.55) (xy 250.19 209.55)
		)
		(stroke
			(width 0)
			(type default)
		)
	)
	(wire
		(pts
			(xy 213.36 214.63) (xy 229.87 214.63)
		)
		(stroke
			(width 0)
			(type default)
		)
	)
	(wire
		(pts
			(xy 285.75 125.73) (xy 285.75 128.27)
		)
		(stroke
			(width 0)
			(type default)
		)
	)
	(wire
		(pts
			(xy 228.6 220.98) (xy 229.87 220.98)
		)
		(stroke
			(width 0)
			(type default)
		)
	)
	(wire
		(pts
			(xy 327.66 205.74) (xy 360.68 205.74)
		)
		(stroke
			(width 0)
			(type default)
		)
	)
	(wire
		(pts
			(xy 116.84 121.92) (xy 116.84 123.19)
		)
		(stroke
			(width 0)
			(type default)
		)
	)
	(wire
		(pts
			(xy 116.84 120.65) (xy 116.84 121.92)
		)
		(stroke
			(width 0)
			(type default)
		)
	)
	(wire
		(pts
			(xy 250.19 223.52) (xy 250.19 224.79)
		)
		(stroke
			(width 0)
			(type default)
		)
	)
	(wire
		(pts
			(xy 317.5 78.74) (xy 317.5 74.93)
		)
		(stroke
			(width 0)
			(type default)
		)
	)
	(wire
		(pts
			(xy 264.16 44.45) (xy 278.13 44.45)
		)
		(stroke
			(width 0)
			(type default)
		)
	)
	(wire
		(pts
			(xy 250.19 218.44) (xy 250.19 217.17)
		)
		(stroke
			(width 0)
			(type default)
		)
	)
	(wire
		(pts
			(xy 270.51 60.96) (xy 270.51 52.07)
		)
		(stroke
			(width 0)
			(type default)
		)
	)
	(wire
		(pts
			(xy 264.16 44.45) (xy 264.16 45.72)
		)
		(stroke
			(width 0)
			(type default)
		)
	)
	(wire
		(pts
			(xy 229.87 218.44) (xy 228.6 218.44)
		)
		(stroke
			(width 0)
			(type default)
		)
	)
	(wire
		(pts
			(xy 302.26 73.66) (xy 302.26 78.74)
		)
		(stroke
			(width 0)
			(type default)
		)
	)
	(wire
		(pts
			(xy 76.2 78.74) (xy 78.74 78.74)
		)
		(stroke
			(width 0)
			(type default)
		)
	)
	(wire
		(pts
			(xy 91.44 190.5) (xy 91.44 193.04)
		)
		(stroke
			(width 0)
			(type default)
		)
	)
	(bus
		(pts
			(xy 326.39 207.01) (xy 326.39 204.47)
		)
		(stroke
			(width 0)
			(type default)
		)
	)
	(wire
		(pts
			(xy 259.08 208.28) (xy 259.08 209.55)
		)
		(stroke
			(width 0)
			(type default)
		)
	)
	(wire
		(pts
			(xy 314.96 138.43) (xy 289.56 138.43)
		)
		(stroke
			(width 0)
			(type default)
		)
	)
	(wire
		(pts
			(xy 76.2 256.54) (xy 92.71 256.54)
		)
		(stroke
			(width 0)
			(type default)
		)
	)
	(wire
		(pts
			(xy 215.9 85.09) (xy 218.44 85.09)
		)
		(stroke
			(width 0)
			(type default)
		)
	)
	(wire
		(pts
			(xy 93.98 60.96) (xy 116.84 60.96)
		)
		(stroke
			(width 0)
			(type default)
		)
	)
	(wire
		(pts
			(xy 218.44 110.49) (xy 218.44 102.87)
		)
		(stroke
			(width 0)
			(type default)
		)
	)
	(wire
		(pts
			(xy 270.51 66.04) (xy 270.51 68.58)
		)
		(stroke
			(width 0)
			(type default)
		)
	)
	(bus
		(pts
			(xy 326.39 209.55) (xy 326.39 212.09)
		)
		(stroke
			(width 0)
			(type default)
		)
	)
	(wire
		(pts
			(xy 250.19 209.55) (xy 259.08 209.55)
		)
		(stroke
			(width 0)
			(type default)
		)
	)
	(wire
		(pts
			(xy 88.9 83.82) (xy 88.9 66.04)
		)
		(stroke
			(width 0)
			(type default)
		)
	)
	(wire
		(pts
			(xy 265.43 68.58) (xy 270.51 68.58)
		)
		(stroke
			(width 0)
			(type default)
		)
	)
	(wire
		(pts
			(xy 91.44 193.04) (xy 76.2 193.04)
		)
		(stroke
			(width 0)
			(type default)
		)
	)
	(wire
		(pts
			(xy 76.2 248.92) (xy 92.71 248.92)
		)
		(stroke
			(width 0)
			(type default)
		)
	)
	(wire
		(pts
			(xy 93.98 38.1) (xy 104.14 38.1)
		)
		(stroke
			(width 0)
			(type default)
		)
	)
	(wire
		(pts
			(xy 76.2 144.78) (xy 90.17 144.78)
		)
		(stroke
			(width 0)
			(type default)
		)
	)
	(wire
		(pts
			(xy 231.14 105.41) (xy 236.22 105.41)
		)
		(stroke
			(width 0)
			(type default)
		)
	)
	(wire
		(pts
			(xy 95.25 162.56) (xy 76.2 162.56)
		)
		(stroke
			(width 0)
			(type default)
		)
	)
	(wire
		(pts
			(xy 76.2 66.04) (xy 82.55 66.04)
		)
		(stroke
			(width 0)
			(type default)
		)
	)
	(wire
		(pts
			(xy 382.27 205.74) (xy 379.73 205.74)
		)
		(stroke
			(width 0)
			(type default)
		)
	)
	(wire
		(pts
			(xy 104.14 36.83) (xy 104.14 38.1)
		)
		(stroke
			(width 0)
			(type default)
		)
	)
	(wire
		(pts
			(xy 264.16 138.43) (xy 264.16 146.05)
		)
		(stroke
			(width 0)
			(type default)
		)
	)
	(wire
		(pts
			(xy 342.9 213.36) (xy 342.9 218.44)
		)
		(stroke
			(width 0)
			(type default)
		)
	)
	(wire
		(pts
			(xy 104.14 193.04) (xy 91.44 193.04)
		)
		(stroke
			(width 0)
			(type default)
		)
	)
	(wire
		(pts
			(xy 250.19 224.79) (xy 247.65 224.79)
		)
		(stroke
			(width 0)
			(type default)
		)
	)
	(wire
		(pts
			(xy 302.26 60.96) (xy 325.12 60.96)
		)
		(stroke
			(width 0)
			(type default)
		)
	)
	(wire
		(pts
			(xy 121.92 142.24) (xy 121.92 139.7)
		)
		(stroke
			(width 0)
			(type default)
		)
	)
	(wire
		(pts
			(xy 278.13 44.45) (xy 278.13 52.07)
		)
		(stroke
			(width 0)
			(type default)
		)
	)
	(wire
		(pts
			(xy 78.74 50.8) (xy 78.74 53.34)
		)
		(stroke
			(width 0)
			(type default)
		)
	)
	(wire
		(pts
			(xy 337.82 76.2) (xy 337.82 78.74)
		)
		(stroke
			(width 0)
			(type default)
		)
	)
	(wire
		(pts
			(xy 228.6 220.98) (xy 228.6 223.52)
		)
		(stroke
			(width 0)
			(type default)
		)
	)
	(wire
		(pts
			(xy 218.44 63.5) (xy 218.44 71.12)
		)
		(stroke
			(width 0)
			(type default)
		)
	)
	(wire
		(pts
			(xy 123.19 142.24) (xy 121.92 142.24)
		)
		(stroke
			(width 0)
			(type default)
		)
	)
	(wire
		(pts
			(xy 250.19 210.82) (xy 250.19 209.55)
		)
		(stroke
			(width 0)
			(type default)
		)
	)
	(wire
		(pts
			(xy 218.44 53.34) (xy 218.44 58.42)
		)
		(stroke
			(width 0)
			(type default)
		)
	)
	(wire
		(pts
			(xy 264.16 71.12) (xy 264.16 73.66)
		)
		(stroke
			(width 0)
			(type default)
		)
	)
	(wire
		(pts
			(xy 349.25 200.66) (xy 349.25 213.36)
		)
		(stroke
			(width 0)
			(type default)
		)
	)
	(wire
		(pts
			(xy 259.08 209.55) (xy 259.08 210.82)
		)
		(stroke
			(width 0)
			(type default)
		)
	)
	(wire
		(pts
			(xy 95.25 172.72) (xy 76.2 172.72)
		)
		(stroke
			(width 0)
			(type default)
		)
	)
	(wire
		(pts
			(xy 120.65 147.32) (xy 123.19 147.32)
		)
		(stroke
			(width 0)
			(type default)
		)
	)
	(wire
		(pts
			(xy 314.96 143.51) (xy 314.96 138.43)
		)
		(stroke
			(width 0)
			(type default)
		)
	)
	(wire
		(pts
			(xy 218.44 100.33) (xy 218.44 102.87)
		)
		(stroke
			(width 0)
			(type default)
		)
	)
	(wire
		(pts
			(xy 259.08 73.66) (xy 264.16 73.66)
		)
		(stroke
			(width 0)
			(type default)
		)
	)
	(bus
		(pts
			(xy 93.98 267.97) (xy 93.98 270.51)
		)
		(stroke
			(width 0)
			(type default)
		)
	)
	(wire
		(pts
			(xy 76.2 71.12) (xy 106.68 71.12)
		)
		(stroke
			(width 0)
			(type default)
		)
	)
	(wire
		(pts
			(xy 317.5 69.85) (xy 317.5 66.04)
		)
		(stroke
			(width 0)
			(type default)
		)
	)
	(wire
		(pts
			(xy 78.74 81.28) (xy 78.74 83.82)
		)
		(stroke
			(width 0)
			(type default)
		)
	)
	(wire
		(pts
			(xy 247.65 224.79) (xy 247.65 223.52)
		)
		(stroke
			(width 0)
			(type default)
		)
	)
	(wire
		(pts
			(xy 83.82 213.36) (xy 76.2 213.36)
		)
		(stroke
			(width 0)
			(type default)
		)
	)
	(wire
		(pts
			(xy 76.2 53.34) (xy 78.74 53.34)
		)
		(stroke
			(width 0)
			(type default)
		)
	)
	(bus
		(pts
			(xy 93.98 255.27) (xy 93.98 252.73)
		)
		(stroke
			(width 0)
			(type default)
		)
	)
	(bus
		(pts
			(xy 93.98 156.21) (xy 93.98 158.75)
		)
		(stroke
			(width 0)
			(type default)
		)
	)
	(bus
		(pts
			(xy 212.09 210.82) (xy 210.82 209.55)
		)
		(stroke
			(width 0)
			(type default)
		)
	)
	(wire
		(pts
			(xy 228.6 107.95) (xy 236.22 107.95)
		)
		(stroke
			(width 0)
			(type default)
		)
	)
	(wire
		(pts
			(xy 264.16 73.66) (xy 264.16 76.2)
		)
		(stroke
			(width 0)
			(type default)
		)
	)
	(wire
		(pts
			(xy 93.98 134.62) (xy 95.25 134.62)
		)
		(stroke
			(width 0)
			(type default)
		)
	)
	(wire
		(pts
			(xy 228.6 107.95) (xy 228.6 110.49)
		)
		(stroke
			(width 0)
			(type default)
		)
	)
	(wire
		(pts
			(xy 382.27 205.74) (xy 382.27 207.01)
		)
		(stroke
			(width 0)
			(type default)
		)
	)
	(wire
		(pts
			(xy 213.36 212.09) (xy 229.87 212.09)
		)
		(stroke
			(width 0)
			(type default)
		)
	)
	(wire
		(pts
			(xy 259.08 76.2) (xy 259.08 73.66)
		)
		(stroke
			(width 0)
			(type default)
		)
	)
	(wire
		(pts
			(xy 82.55 38.1) (xy 93.98 38.1)
		)
		(stroke
			(width 0)
			(type default)
		)
	)
	(wire
		(pts
			(xy 256.54 132.08) (xy 256.54 133.35)
		)
		(stroke
			(width 0)
			(type default)
		)
	)
	(wire
		(pts
			(xy 93.98 38.1) (xy 93.98 40.64)
		)
		(stroke
			(width 0)
			(type default)
		)
	)
	(bus
		(pts
			(xy 93.98 252.73) (xy 95.25 251.46)
		)
		(stroke
			(width 0)
			(type default)
		)
	)
	(wire
		(pts
			(xy 309.88 63.5) (xy 322.58 63.5)
		)
		(stroke
			(width 0)
			(type default)
		)
	)
	(wire
		(pts
			(xy 135.89 58.42) (xy 138.43 58.42)
		)
		(stroke
			(width 0)
			(type default)
		)
	)
	(wire
		(pts
			(xy 307.34 68.58) (xy 307.34 71.12)
		)
		(stroke
			(width 0)
			(type default)
		)
	)
	(wire
		(pts
			(xy 327.66 213.36) (xy 342.9 213.36)
		)
		(stroke
			(width 0)
			(type default)
		)
	)
	(wire
		(pts
			(xy 360.68 242.57) (xy 360.68 246.38)
		)
		(stroke
			(width 0)
			(type default)
		)
	)
	(bus
		(pts
			(xy 93.98 267.97) (xy 95.25 266.7)
		)
		(stroke
			(width 0)
			(type default)
		)
	)
	(wire
		(pts
			(xy 349.25 193.04) (xy 356.87 193.04)
		)
		(stroke
			(width 0)
			(type default)
		)
	)
	(bus
		(pts
			(xy 93.98 152.4) (xy 95.25 151.13)
		)
		(stroke
			(width 0)
			(type default)
		)
	)
	(wire
		(pts
			(xy 264.16 71.12) (xy 279.4 71.12)
		)
		(stroke
			(width 0)
			(type default)
		)
	)
	(wire
		(pts
			(xy 317.5 66.04) (xy 299.72 66.04)
		)
		(stroke
			(width 0)
			(type default)
		)
	)
	(bus
		(pts
			(xy 93.98 242.57) (xy 93.98 240.03)
		)
		(stroke
			(width 0)
			(type default)
		)
	)
	(wire
		(pts
			(xy 345.44 210.82) (xy 345.44 215.9)
		)
		(stroke
			(width 0)
			(type default)
		)
	)
	(wire
		(pts
			(xy 278.13 60.96) (xy 279.4 60.96)
		)
		(stroke
			(width 0)
			(type default)
		)
	)
	(wire
		(pts
			(xy 76.2 264.16) (xy 92.71 264.16)
		)
		(stroke
			(width 0)
			(type default)
		)
	)
	(wire
		(pts
			(xy 100.33 162.56) (xy 102.87 162.56)
		)
		(stroke
			(width 0)
			(type default)
		)
	)
	(wire
		(pts
			(xy 264.16 146.05) (xy 269.24 146.05)
		)
		(stroke
			(width 0)
			(type default)
		)
	)
	(wire
		(pts
			(xy 228.6 204.47) (xy 228.6 218.44)
		)
		(stroke
			(width 0)
			(type default)
		)
	)
	(polyline
		(pts
			(xy 177.8 254) (xy 299.72 254)
		)
		(stroke
			(width 0)
			(type dash)
		)
	)
	(wire
		(pts
			(xy 285.75 128.27) (xy 285.75 129.54)
		)
		(stroke
			(width 0)
			(type default)
		)
	)
	(polyline
		(pts
			(xy 177.8 12.7) (xy 177.8 170.18)
		)
		(stroke
			(width 0)
			(type dash)
		)
	)
	(wire
		(pts
			(xy 256.54 143.51) (xy 256.54 151.13)
		)
		(stroke
			(width 0)
			(type default)
		)
	)
	(wire
		(pts
			(xy 337.82 60.96) (xy 345.44 60.96)
		)
		(stroke
			(width 0)
			(type default)
		)
	)
	(wire
		(pts
			(xy 123.19 139.7) (xy 121.92 139.7)
		)
		(stroke
			(width 0)
			(type default)
		)
	)
	(wire
		(pts
			(xy 76.2 238.76) (xy 87.63 238.76)
		)
		(stroke
			(width 0)
			(type default)
		)
	)
	(wire
		(pts
			(xy 302.26 58.42) (xy 302.26 60.96)
		)
		(stroke
			(width 0)
			(type default)
		)
	)
	(wire
		(pts
			(xy 382.27 193.04) (xy 382.27 205.74)
		)
		(stroke
			(width 0)
			(type default)
		)
	)
	(wire
		(pts
			(xy 264.16 132.08) (xy 264.16 133.35)
		)
		(stroke
			(width 0)
			(type default)
		)
	)
	(wire
		(pts
			(xy 233.68 140.97) (xy 248.92 140.97)
		)
		(stroke
			(width 0)
			(type default)
		)
	)
	(wire
		(pts
			(xy 331.47 158.75) (xy 331.47 152.4)
		)
		(stroke
			(width 0)
			(type default)
		)
	)
	(wire
		(pts
			(xy 116.84 60.96) (xy 116.84 63.5)
		)
		(stroke
			(width 0)
			(type default)
		)
	)
	(wire
		(pts
			(xy 299.72 63.5) (xy 304.8 63.5)
		)
		(stroke
			(width 0)
			(type default)
		)
	)
	(wire
		(pts
			(xy 342.9 218.44) (xy 360.68 218.44)
		)
		(stroke
			(width 0)
			(type default)
		)
	)
	(bus
		(pts
			(xy 93.98 245.11) (xy 93.98 247.65)
		)
		(stroke
			(width 0)
			(type default)
		)
	)
	(wire
		(pts
			(xy 138.43 55.88) (xy 138.43 58.42)
		)
		(stroke
			(width 0)
			(type default)
		)
	)
	(bus
		(pts
			(xy 325.12 203.2) (xy 317.5 203.2)
		)
		(stroke
			(width 0)
			(type default)
		)
	)
	(wire
		(pts
			(xy 292.1 146.05) (xy 292.1 143.51)
		)
		(stroke
			(width 0)
			(type default)
		)
	)
	(wire
		(pts
			(xy 92.71 160.02) (xy 76.2 160.02)
		)
		(stroke
			(width 0)
			(type default)
		)
	)
	(wire
		(pts
			(xy 270.51 68.58) (xy 279.4 68.58)
		)
		(stroke
			(width 0)
			(type default)
		)
	)
	(wire
		(pts
			(xy 76.2 246.38) (xy 92.71 246.38)
		)
		(stroke
			(width 0)
			(type default)
		)
	)
	(wire
		(pts
			(xy 330.2 60.96) (xy 331.47 60.96)
		)
		(stroke
			(width 0)
			(type default)
		)
	)
	(wire
		(pts
			(xy 312.42 148.59) (xy 323.85 148.59)
		)
		(stroke
			(width 0)
			(type default)
		)
	)
	(wire
		(pts
			(xy 138.43 63.5) (xy 138.43 58.42)
		)
		(stroke
			(width 0)
			(type default)
		)
	)
	(wire
		(pts
			(xy 218.44 115.57) (xy 218.44 118.11)
		)
		(stroke
			(width 0)
			(type default)
		)
	)
	(wire
		(pts
			(xy 78.74 78.74) (xy 78.74 81.28)
		)
		(stroke
			(width 0)
			(type default)
		)
	)
	(wire
		(pts
			(xy 99.06 190.5) (xy 99.06 195.58)
		)
		(stroke
			(width 0)
			(type default)
		)
	)
	(wire
		(pts
			(xy 355.6 231.14) (xy 360.68 231.14)
		)
		(stroke
			(width 0)
			(type default)
		)
	)
	(wire
		(pts
			(xy 289.56 148.59) (xy 294.64 148.59)
		)
		(stroke
			(width 0)
			(type default)
		)
	)
	(bus
		(pts
			(xy 95.25 259.08) (xy 96.52 259.08)
		)
		(stroke
			(width 0)
			(type default)
		)
	)
	(wire
		(pts
			(xy 76.2 195.58) (xy 99.06 195.58)
		)
		(stroke
			(width 0)
			(type default)
		)
	)
	(wire
		(pts
			(xy 102.87 162.56) (xy 102.87 161.29)
		)
		(stroke
			(width 0)
			(type default)
		)
	)
	(wire
		(pts
			(xy 379.73 218.44) (xy 381 218.44)
		)
		(stroke
			(width 0)
			(type default)
		)
	)
	(polyline
		(pts
			(xy 177.8 170.18) (xy 177.8 254)
		)
		(stroke
			(width 0)
			(type dash)
		)
	)
	(wire
		(pts
			(xy 76.2 269.24) (xy 92.71 269.24)
		)
		(stroke
			(width 0)
			(type default)
		)
	)
	(label "SER1.RX"
		(at 87.63 264.16 180)
		(effects
			(font
				(size 1.27 1.27)
			)
			(justify right bottom)
		)
	)
	(label "~{SUS_S5}"
		(at 95.25 172.72 180)
		(effects
			(font
				(size 1.27 1.27)
			)
			(justify right bottom)
		)
	)
	(label "~{TYPE1}"
		(at 233.68 143.51 0)
		(effects
			(font
				(size 1.27 1.27)
			)
			(justify left bottom)
		)
	)
	(label "PWRBTN"
		(at 218.44 71.12 0)
		(effects
			(font
				(size 1.27 1.27)
			)
			(justify left bottom)
		)
	)
	(label "~{TYPE1}"
		(at 83.82 215.9 180)
		(effects
			(font
				(size 1.27 1.27)
			)
			(justify right bottom)
		)
	)
	(label "~{TYPE2}"
		(at 83.82 218.44 180)
		(effects
			(font
				(size 1.27 1.27)
			)
			(justify right bottom)
		)
	)
	(label "MAFS_POWER"
		(at 361.95 193.04 0)
		(effects
			(font
				(size 1.27 1.27)
			)
			(justify left bottom)
		)
	)
	(label "SPI.~{CS}"
		(at 328.93 213.36 0)
		(effects
			(font
				(size 1.27 1.27)
			)
			(justify left bottom)
		)
	)
	(label "I2C.SCL"
		(at 87.63 269.24 180)
		(effects
			(font
				(size 1.27 1.27)
			)
			(justify right bottom)
		)
	)
	(label "I2C.SDA"
		(at 87.63 271.78 180)
		(effects
			(font
				(size 1.27 1.27)
			)
			(justify right bottom)
		)
	)
	(label "~{SUS_S5}"
		(at 246.38 68.58 0)
		(effects
			(font
				(size 1.27 1.27)
			)
			(justify left bottom)
		)
	)
	(label "SPI{SPI}"
		(at 102.87 238.76 180)
		(effects
			(font
				(size 1.27 1.27)
			)
			(justify right bottom)
		)
	)
	(label "SMBus.~{INT}"
		(at 91.44 154.94 180)
		(effects
			(font
				(size 1.27 1.27)
			)
			(justify right bottom)
		)
	)
	(label "SPI.MISO"
		(at 87.63 241.3 180)
		(effects
			(font
				(size 1.27 1.27)
			)
			(justify right bottom)
		)
	)
	(label "SER0.TX"
		(at 87.63 254 180)
		(effects
			(font
				(size 1.27 1.27)
			)
			(justify right bottom)
		)
	)
	(label "~{CW_PWRBTN}"
		(at 322.58 63.5 180)
		(effects
			(font
				(size 1.27 1.27)
			)
			(justify right bottom)
		)
	)
	(label "SPI.CLK"
		(at 328.93 210.82 0)
		(effects
			(font
				(size 1.27 1.27)
			)
			(justify left bottom)
		)
	)
	(label "~{TYPE2}"
		(at 233.68 146.05 0)
		(effects
			(font
				(size 1.27 1.27)
			)
			(justify left bottom)
		)
	)
	(label "I2C{I2C}"
		(at 201.93 209.55 0)
		(effects
			(font
				(size 1.27 1.27)
			)
			(justify left bottom)
		)
	)
	(label "I2C.SCL"
		(at 222.25 212.09 180)
		(effects
			(font
				(size 1.27 1.27)
			)
			(justify right bottom)
		)
	)
	(label "~{COM7}"
		(at 321.31 148.59 180)
		(effects
			(font
				(size 1.27 1.27)
			)
			(justify right bottom)
		)
	)
	(label "SPI.MOSI"
		(at 87.63 246.38 180)
		(effects
			(font
				(size 1.27 1.27)
			)
			(justify right bottom)
		)
	)
	(label "PWRBTN"
		(at 180.34 99.06 0)
		(effects
			(font
				(size 1.27 1.27)
			)
			(justify left bottom)
		)
	)
	(label "I2C.SDA"
		(at 222.25 214.63 180)
		(effects
			(font
				(size 1.27 1.27)
			)
			(justify right bottom)
		)
	)
	(label "SPI.MOSI"
		(at 328.93 205.74 0)
		(effects
			(font
				(size 1.27 1.27)
			)
			(justify left bottom)
		)
	)
	(label "SPI.CLK"
		(at 87.63 243.84 180)
		(effects
			(font
				(size 1.27 1.27)
			)
			(justify right bottom)
		)
	)
	(label "~{TYPE0}"
		(at 83.82 213.36 180)
		(effects
			(font
				(size 1.27 1.27)
			)
			(justify right bottom)
		)
	)
	(label "~{BIOS_DIS0}"
		(at 97.79 132.08 180)
		(effects
			(font
				(size 1.27 1.27)
			)
			(justify right bottom)
		)
	)
	(label "SMBus.SCL"
		(at 91.44 157.48 180)
		(effects
			(font
				(size 1.27 1.27)
			)
			(justify right bottom)
		)
	)
	(label "SER1.TX"
		(at 87.63 261.62 180)
		(effects
			(font
				(size 1.27 1.27)
			)
			(justify right bottom)
		)
	)
	(label "SMBus.SDA"
		(at 91.44 160.02 180)
		(effects
			(font
				(size 1.27 1.27)
			)
			(justify right bottom)
		)
	)
	(label "~{TYPE0}"
		(at 233.68 140.97 0)
		(effects
			(font
				(size 1.27 1.27)
			)
			(justify left bottom)
		)
	)
	(label "SPI.MISO"
		(at 328.93 208.28 0)
		(effects
			(font
				(size 1.27 1.27)
			)
			(justify left bottom)
		)
	)
	(label "SPI.~{CS}"
		(at 87.63 248.92 180)
		(effects
			(font
				(size 1.27 1.27)
			)
			(justify right bottom)
		)
	)
	(label "SPI_POWER"
		(at 311.15 190.5 0)
		(effects
			(font
				(size 1.27 1.27)
			)
			(justify left bottom)
		)
	)
	(label "~{BIOS_DIS0}"
		(at 335.28 231.14 0)
		(effects
			(font
				(size 1.27 1.27)
			)
			(justify left bottom)
		)
	)
	(label "SPI{SPI}"
		(at 317.5 203.2 0)
		(effects
			(font
				(size 1.27 1.27)
			)
			(justify left bottom)
		)
	)
	(label "SER0.RX"
		(at 87.63 256.54 180)
		(effects
			(font
				(size 1.27 1.27)
			)
			(justify right bottom)
		)
	)
	(label "~{CW_PWRBTN}"
		(at 88.9 147.32 180)
		(effects
			(font
				(size 1.27 1.27)
			)
			(justify right bottom)
		)
	)
	(label "SPI_POWER"
		(at 87.63 238.76 180)
		(effects
			(font
				(size 1.27 1.27)
			)
			(justify right bottom)
		)
	)
	(hierarchical_label "FAM_TACH"
		(shape input)
		(at 104.14 195.58 0)
		(effects
			(font
				(size 1.27 1.27)
			)
			(justify left)
		)
	)
	(hierarchical_label "~{CB_RESET}"
		(shape output)
		(at 147.32 144.78 0)
		(effects
			(font
				(size 1.27 1.27)
			)
			(justify left)
		)
	)
	(hierarchical_label "I2C{I2C}"
		(shape output)
		(at 96.52 266.7 0)
		(effects
			(font
				(size 1.27 1.27)
			)
			(justify left)
		)
	)
	(hierarchical_label "FAN_PWM"
		(shape output)
		(at 104.14 193.04 0)
		(effects
			(font
				(size 1.27 1.27)
			)
			(justify left)
		)
	)
	(hierarchical_label "SER1{UART}"
		(shape bidirectional)
		(at 96.52 259.08 0)
		(effects
			(font
				(size 1.27 1.27)
			)
			(justify left)
		)
	)
	(hierarchical_label "SER0{UART}"
		(shape bidirectional)
		(at 96.52 251.46 0)
		(effects
			(font
				(size 1.27 1.27)
			)
			(justify left)
		)
	)
	(hierarchical_label "PWR_OK"
		(shape input)
		(at 90.17 144.78 0)
		(effects
			(font
				(size 1.27 1.27)
			)
			(justify left)
		)
	)
	(hierarchical_label "PSON"
		(shape output)
		(at 345.44 60.96 0)
		(effects
			(font
				(size 1.27 1.27)
			)
			(justify left)
		)
	)
	(hierarchical_label "SMBus{I2C}"
		(shape output)
		(at 97.79 151.13 0)
		(effects
			(font
				(size 1.27 1.27)
			)
			(justify left)
		)
	)
	(symbol
		(lib_id "antmicroResistors0402:R_10k_0402")
		(at 248.92 138.43 90)
		(unit 1)
		(exclude_from_sim no)
		(in_bom yes)
		(on_board yes)
		(dnp no)
		(property "Reference" "R167"
			(at 250.19 134.62 90)
			(effects
				(font
					(size 1.27 1.27)
					(thickness 0.15)
				)
				(justify right)
			)
		)
		(property "Value" "R_10k_0402"
			(at 261.62 118.11 0)
			(effects
				(font
					(size 1.27 1.27)
					(thickness 0.15)
				)
				(justify left bottom)
				(hide yes)
			)
		)
		(property "Footprint" "antmicro-footprints:R_0402_1005Metric"
			(at 264.16 118.11 0)
			(effects
				(font
					(size 1.27 1.27)
					(thickness 0.15)
				)
				(justify left bottom)
				(hide yes)
			)
		)
		(property "Datasheet" "https://www.bourns.com/docs/product-datasheets/cr.pdf"
			(at 266.7 118.11 0)
			(effects
				(font
					(size 1.27 1.27)
					(thickness 0.15)
				)
				(justify left bottom)
				(hide yes)
			)
		)
		(property "Description" ""
			(at 248.92 138.43 0)
			(effects
				(font
					(size 1.27 1.27)
				)
				(hide yes)
			)
		)
		(property "MPN" "CR0402-FX-1002GLF"
			(at 269.24 118.11 0)
			(effects
				(font
					(size 1.27 1.27)
					(thickness 0.15)
				)
				(justify left bottom)
				(hide yes)
			)
		)
		(property "Manufacturer" "Bourns"
			(at 271.78 118.11 0)
			(effects
				(font
					(size 1.27 1.27)
					(thickness 0.15)
				)
				(justify left bottom)
				(hide yes)
			)
		)
		(property "License" "Apache-2.0"
			(at 274.32 118.11 0)
			(effects
				(font
					(size 1.27 1.27)
					(thickness 0.15)
				)
				(justify left bottom)
				(hide yes)
			)
		)
		(property "Author" "Antmicro"
			(at 276.86 118.11 0)
			(effects
				(font
					(size 1.27 1.27)
					(thickness 0.15)
				)
				(justify left bottom)
				(hide yes)
			)
		)
		(property "Val" "10k"
			(at 250.19 137.16 90)
			(effects
				(font
					(size 1.27 1.27)
					(thickness 0.15)
				)
				(justify right)
			)
		)
		(property "Tolerance" "1%"
			(at 259.08 118.11 0)
			(effects
				(font
					(size 1.27 1.27)
				)
				(justify left bottom)
				(hide yes)
			)
		)
		(property "Public" "False"
			(at 279.4 118.11 0)
			(effects
				(font
					(size 1.27 1.27)
				)
				(justify left bottom)
				(hide yes)
			)
		)
		(pin "1"
		)
		(pin "2"
		)
		(instances
			(project "com-express-7-baseboard"
				(path ""
					(reference "R167")
					(unit 1)
				)
			)
		)
	)
	(symbol
		(lib_id "antmicroTestPoints:TP_0.75mm_SMD")
		(at 76.2 182.88 0)
		(unit 1)
		(exclude_from_sim no)
		(in_bom no)
		(on_board yes)
		(dnp no)
		(fields_autoplaced yes)
		(property "Reference" "TP38"
			(at 81.28 182.88 0)
			(effects
				(font
					(size 1.27 1.27)
					(thickness 0.15)
				)
				(justify left)
			)
		)
		(property "Value" "TP_0.75mm_SMD"
			(at 86.995 186.69 0)
			(effects
				(font
					(size 1.27 1.27)
					(thickness 0.15)
				)
				(justify left bottom)
				(hide yes)
			)
		)
		(property "Footprint" "antmicro-footprints:TP_SMD_0.75mm"
			(at 86.995 189.23 0)
			(effects
				(font
					(size 1.27 1.27)
					(thickness 0.15)
				)
				(justify left bottom)
				(hide yes)
			)
		)
		(property "Datasheet" ""
			(at 93.98 195.58 0)
			(effects
				(font
					(size 1.27 1.27)
					(thickness 0.15)
				)
				(justify left bottom)
				(hide yes)
			)
		)
		(property "Description" ""
			(at 76.2 182.88 0)
			(effects
				(font
					(size 1.27 1.27)
				)
				(hide yes)
			)
		)
		(property "MPN" ""
			(at 86.995 194.31 0)
			(effects
				(font
					(size 1.27 1.27)
					(thickness 0.15)
				)
				(justify left bottom)
				(hide yes)
			)
		)
		(property "Manufacturer" ""
			(at 86.995 189.23 0)
			(effects
				(font
					(size 1.27 1.27)
					(thickness 0.15)
				)
				(justify left bottom)
				(hide yes)
			)
		)
		(property "Author" "Antmicro"
			(at 86.995 191.77 0)
			(effects
				(font
					(size 1.27 1.27)
					(thickness 0.15)
				)
				(justify left bottom)
				(hide yes)
			)
		)
		(property "License" "Apache-2.0"
			(at 86.995 194.31 0)
			(effects
				(font
					(size 1.27 1.27)
					(thickness 0.15)
				)
				(justify left bottom)
				(hide yes)
			)
		)
		(property "Public" "False"
			(at 86.36 196.85 0)
			(effects
				(font
					(size 1.27 1.27)
				)
				(justify left bottom)
				(hide yes)
			)
		)
		(pin "1"
		)
		(instances
			(project "com-express-7-baseboard"
				(path ""
					(reference "TP38")
					(unit 1)
				)
			)
		)
	)
	(symbol
		(lib_id "antmicroMemory:W25Q32FV_SOIC-8")
		(at 360.68 205.74 0)
		(unit 1)
		(exclude_from_sim no)
		(in_bom yes)
		(on_board yes)
		(dnp no)
		(property "Reference" "U36"
			(at 370.205 198.12 0)
			(effects
				(font
					(size 1.27 1.27)
					(thickness 0.15)
				)
			)
		)
		(property "Value" "W25Q32FV_SOIC-8"
			(at 370.205 200.66 0)
			(effects
				(font
					(size 1.27 1.27)
					(thickness 0.15)
				)
				(hide yes)
			)
		)
		(property "Footprint" "antmicro-footprints:SOIC-8_5.3x5.3x2mm_P1.27mm"
			(at 402.59 214.63 0)
			(effects
				(font
					(size 1.27 1.27)
					(thickness 0.15)
				)
				(justify left bottom)
				(hide yes)
			)
		)
		(property "Datasheet" "https://media.digikey.com/pdf/Data%20Sheets/Winbond%20PDFs/W25Q32FV.pdf"
			(at 402.59 217.17 0)
			(effects
				(font
					(size 1.27 1.27)
					(thickness 0.15)
				)
				(justify left bottom)
				(hide yes)
			)
		)
		(property "Description" ""
			(at 360.68 205.74 0)
			(effects
				(font
					(size 1.27 1.27)
				)
				(hide yes)
			)
		)
		(property "Manufacturer" "Winbond"
			(at 402.59 219.71 0)
			(effects
				(font
					(size 1.27 1.27)
					(thickness 0.15)
				)
				(justify left bottom)
				(hide yes)
			)
		)
		(property "MPN" "W25Q32FVSSIG"
			(at 363.22 201.93 0)
			(effects
				(font
					(size 1.27 1.27)
					(thickness 0.15)
				)
				(justify left bottom)
			)
		)
		(property "Author" "Antmicro"
			(at 402.59 224.79 0)
			(effects
				(font
					(size 1.27 1.27)
					(thickness 0.15)
				)
				(justify left bottom)
				(hide yes)
			)
		)
		(property "License" "Apache-2.0"
			(at 402.59 227.33 0)
			(effects
				(font
					(size 1.27 1.27)
					(thickness 0.15)
				)
				(justify left bottom)
				(hide yes)
			)
		)
		(pin "8"
		)
		(pin "7"
		)
		(pin "2"
		)
		(pin "5"
		)
		(pin "4"
		)
		(pin "3"
		)
		(pin "1"
		)
		(pin "6"
		)
		(instances
			(project "com-express-7-baseboard"
				(path ""
					(reference "U36")
					(unit 1)
				)
			)
		)
	)
	(symbol
		(lib_id "antmicroTestPoints:TP_0.75mm_SMD")
		(at 76.2 106.68 0)
		(unit 1)
		(exclude_from_sim no)
		(in_bom no)
		(on_board yes)
		(dnp no)
		(fields_autoplaced yes)
		(property "Reference" "TP22"
			(at 81.28 106.68 0)
			(effects
				(font
					(size 1.27 1.27)
					(thickness 0.15)
				)
				(justify left)
			)
		)
		(property "Value" "TP_0.75mm_SMD"
			(at 86.995 110.49 0)
			(effects
				(font
					(size 1.27 1.27)
					(thickness 0.15)
				)
				(justify left bottom)
				(hide yes)
			)
		)
		(property "Footprint" "antmicro-footprints:TP_SMD_0.75mm"
			(at 86.995 113.03 0)
			(effects
				(font
					(size 1.27 1.27)
					(thickness 0.15)
				)
				(justify left bottom)
				(hide yes)
			)
		)
		(property "Datasheet" ""
			(at 93.98 119.38 0)
			(effects
				(font
					(size 1.27 1.27)
					(thickness 0.15)
				)
				(justify left bottom)
				(hide yes)
			)
		)
		(property "Description" ""
			(at 76.2 106.68 0)
			(effects
				(font
					(size 1.27 1.27)
				)
				(hide yes)
			)
		)
		(property "MPN" ""
			(at 86.995 118.11 0)
			(effects
				(font
					(size 1.27 1.27)
					(thickness 0.15)
				)
				(justify left bottom)
				(hide yes)
			)
		)
		(property "Manufacturer" ""
			(at 86.995 113.03 0)
			(effects
				(font
					(size 1.27 1.27)
					(thickness 0.15)
				)
				(justify left bottom)
				(hide yes)
			)
		)
		(property "Author" "Antmicro"
			(at 86.995 115.57 0)
			(effects
				(font
					(size 1.27 1.27)
					(thickness 0.15)
				)
				(justify left bottom)
				(hide yes)
			)
		)
		(property "License" "Apache-2.0"
			(at 86.995 118.11 0)
			(effects
				(font
					(size 1.27 1.27)
					(thickness 0.15)
				)
				(justify left bottom)
				(hide yes)
			)
		)
		(property "Public" "False"
			(at 86.36 120.65 0)
			(effects
				(font
					(size 1.27 1.27)
				)
				(justify left bottom)
				(hide yes)
			)
		)
		(pin "1"
		)
		(instances
			(project "com-express-7-baseboard"
				(path ""
					(reference "TP22")
					(unit 1)
				)
			)
		)
	)
	(symbol
		(lib_id "antmicroTestPoints:TP_0.75mm_SMD")
		(at 76.2 185.42 0)
		(unit 1)
		(exclude_from_sim no)
		(in_bom no)
		(on_board yes)
		(dnp no)
		(fields_autoplaced yes)
		(property "Reference" "TP39"
			(at 81.28 185.42 0)
			(effects
				(font
					(size 1.27 1.27)
					(thickness 0.15)
				)
				(justify left)
			)
		)
		(property "Value" "TP_0.75mm_SMD"
			(at 86.995 189.23 0)
			(effects
				(font
					(size 1.27 1.27)
					(thickness 0.15)
				)
				(justify left bottom)
				(hide yes)
			)
		)
		(property "Footprint" "antmicro-footprints:TP_SMD_0.75mm"
			(at 86.995 191.77 0)
			(effects
				(font
					(size 1.27 1.27)
					(thickness 0.15)
				)
				(justify left bottom)
				(hide yes)
			)
		)
		(property "Datasheet" ""
			(at 93.98 198.12 0)
			(effects
				(font
					(size 1.27 1.27)
					(thickness 0.15)
				)
				(justify left bottom)
				(hide yes)
			)
		)
		(property "Description" ""
			(at 76.2 185.42 0)
			(effects
				(font
					(size 1.27 1.27)
				)
				(hide yes)
			)
		)
		(property "MPN" ""
			(at 86.995 196.85 0)
			(effects
				(font
					(size 1.27 1.27)
					(thickness 0.15)
				)
				(justify left bottom)
				(hide yes)
			)
		)
		(property "Manufacturer" ""
			(at 86.995 191.77 0)
			(effects
				(font
					(size 1.27 1.27)
					(thickness 0.15)
				)
				(justify left bottom)
				(hide yes)
			)
		)
		(property "Author" "Antmicro"
			(at 86.995 194.31 0)
			(effects
				(font
					(size 1.27 1.27)
					(thickness 0.15)
				)
				(justify left bottom)
				(hide yes)
			)
		)
		(property "License" "Apache-2.0"
			(at 86.995 196.85 0)
			(effects
				(font
					(size 1.27 1.27)
					(thickness 0.15)
				)
				(justify left bottom)
				(hide yes)
			)
		)
		(property "Public" "False"
			(at 86.36 199.39 0)
			(effects
				(font
					(size 1.27 1.27)
				)
				(justify left bottom)
				(hide yes)
			)
		)
		(pin "1"
		)
		(instances
			(project "com-express-7-baseboard"
				(path ""
					(reference "TP39")
					(unit 1)
				)
			)
		)
	)
	(symbol
		(lib_id "antmicroTestPoints:TP_0.75mm_SMD")
		(at 76.2 220.98 0)
		(unit 1)
		(exclude_from_sim no)
		(in_bom no)
		(on_board yes)
		(dnp no)
		(fields_autoplaced yes)
		(property "Reference" "TP42"
			(at 81.28 220.98 0)
			(effects
				(font
					(size 1.27 1.27)
					(thickness 0.15)
				)
				(justify left)
				(hide yes)
			)
		)
		(property "Value" "TP_0.75mm_SMD"
			(at 86.995 224.79 0)
			(effects
				(font
					(size 1.27 1.27)
					(thickness 0.15)
				)
				(justify left bottom)
				(hide yes)
			)
		)
		(property "Footprint" "antmicro-footprints:TP_SMD_0.75mm"
			(at 86.995 227.33 0)
			(effects
				(font
					(size 1.27 1.27)
					(thickness 0.15)
				)
				(justify left bottom)
				(hide yes)
			)
		)
		(property "Datasheet" ""
			(at 93.98 233.68 0)
			(effects
				(font
					(size 1.27 1.27)
					(thickness 0.15)
				)
				(justify left bottom)
				(hide yes)
			)
		)
		(property "Description" ""
			(at 76.2 220.98 0)
			(effects
				(font
					(size 1.27 1.27)
				)
				(hide yes)
			)
		)
		(property "MPN" ""
			(at 86.995 232.41 0)
			(effects
				(font
					(size 1.27 1.27)
					(thickness 0.15)
				)
				(justify left bottom)
				(hide yes)
			)
		)
		(property "Manufacturer" ""
			(at 86.995 227.33 0)
			(effects
				(font
					(size 1.27 1.27)
					(thickness 0.15)
				)
				(justify left bottom)
				(hide yes)
			)
		)
		(property "Author" "Antmicro"
			(at 86.995 229.87 0)
			(effects
				(font
					(size 1.27 1.27)
					(thickness 0.15)
				)
				(justify left bottom)
				(hide yes)
			)
		)
		(property "License" "Apache-2.0"
			(at 86.995 232.41 0)
			(effects
				(font
					(size 1.27 1.27)
					(thickness 0.15)
				)
				(justify left bottom)
				(hide yes)
			)
		)
		(property "Public" "False"
			(at 86.36 234.95 0)
			(effects
				(font
					(size 1.27 1.27)
				)
				(justify left bottom)
				(hide yes)
			)
		)
		(pin "1"
		)
		(instances
			(project "com-express-7-baseboard"
				(path ""
					(reference "TP42")
					(unit 1)
				)
			)
		)
	)
	(symbol
		(lib_id "antmicroCapacitors0402:C_1u_0402")
		(at 307.34 76.2 90)
		(unit 1)
		(exclude_from_sim no)
		(in_bom yes)
		(on_board yes)
		(dnp no)
		(fields_autoplaced yes)
		(property "Reference" "C206"
			(at 309.88 72.3836 90)
			(effects
				(font
					(size 1.27 1.27)
					(thickness 0.15)
				)
				(justify right)
			)
		)
		(property "Value" "C_1u_0402"
			(at 317.5 55.88 0)
			(effects
				(font
					(size 1.27 1.27)
					(thickness 0.15)
				)
				(justify left bottom)
				(hide yes)
			)
		)
		(property "Footprint" "antmicro-footprints:C_0402_1005Metric"
			(at 320.04 55.88 0)
			(effects
				(font
					(size 1.27 1.27)
					(thickness 0.15)
				)
				(justify left bottom)
				(hide yes)
			)
		)
		(property "Datasheet" "https://product.tdk.com/en/search/capacitor/ceramic/mlcc/info?part_no=C1005X6S1A105K050BC"
			(at 322.58 55.88 0)
			(effects
				(font
					(size 1.27 1.27)
					(thickness 0.15)
				)
				(justify left bottom)
				(hide yes)
			)
		)
		(property "Description" ""
			(at 307.34 76.2 0)
			(effects
				(font
					(size 1.27 1.27)
				)
				(hide yes)
			)
		)
		(property "MPN" "C1005X6S1A105K050BC"
			(at 325.12 55.88 0)
			(effects
				(font
					(size 1.27 1.27)
					(thickness 0.15)
				)
				(justify left bottom)
				(hide yes)
			)
		)
		(property "Manufacturer" "TDK"
			(at 327.66 55.88 0)
			(effects
				(font
					(size 1.27 1.27)
					(thickness 0.15)
				)
				(justify left bottom)
				(hide yes)
			)
		)
		(property "License" "Apache-2.0"
			(at 330.2 55.88 0)
			(effects
				(font
					(size 1.27 1.27)
					(thickness 0.15)
				)
				(justify left bottom)
				(hide yes)
			)
		)
		(property "Author" "Antmicro"
			(at 332.74 55.88 0)
			(effects
				(font
					(size 1.27 1.27)
					(thickness 0.15)
				)
				(justify left bottom)
				(hide yes)
			)
		)
		(property "Val" "1u"
			(at 309.88 74.9236 90)
			(effects
				(font
					(size 1.27 1.27)
					(thickness 0.15)
				)
				(justify right)
			)
		)
		(property "Voltage" ""
			(at 335.28 55.88 0)
			(effects
				(font
					(size 1.27 1.27)
				)
				(justify left bottom)
				(hide yes)
			)
		)
		(property "Dielectric" ""
			(at 337.82 55.88 0)
			(effects
				(font
					(size 1.27 1.27)
				)
				(justify left bottom)
				(hide yes)
			)
		)
		(property "Public" "False"
			(at 340.36 55.88 0)
			(effects
				(font
					(size 1.27 1.27)
				)
				(justify left bottom)
				(hide yes)
			)
		)
		(pin "2"
		)
		(pin "1"
		)
		(instances
			(project "com-express-7-baseboard"
				(path ""
					(reference "C206")
					(unit 1)
				)
			)
		)
	)
	(symbol
		(lib_id "antmicroResistors0402:R_1k_0402")
		(at 250.19 215.9 90)
		(unit 1)
		(exclude_from_sim no)
		(in_bom yes)
		(on_board yes)
		(dnp yes)
		(property "Reference" "R170"
			(at 251.46 210.82 90)
			(effects
				(font
					(size 1.27 1.27)
					(thickness 0.15)
				)
				(justify right)
			)
		)
		(property "Value" "R_1k_0402"
			(at 262.89 195.58 0)
			(effects
				(font
					(size 1.27 1.27)
					(thickness 0.15)
				)
				(justify left bottom)
				(hide yes)
			)
		)
		(property "Footprint" "antmicro-footprints:R_0402_1005Metric"
			(at 265.43 195.58 0)
			(effects
				(font
					(size 1.27 1.27)
					(thickness 0.15)
				)
				(justify left bottom)
				(hide yes)
			)
		)
		(property "Datasheet" "https://www.bourns.com/docs/product-datasheets/cr.pdf"
			(at 267.97 195.58 0)
			(effects
				(font
					(size 1.27 1.27)
					(thickness 0.15)
				)
				(justify left bottom)
				(hide yes)
			)
		)
		(property "Description" ""
			(at 250.19 215.9 0)
			(effects
				(font
					(size 1.27 1.27)
				)
				(hide yes)
			)
		)
		(property "MPN" "CR0402-FX-1001GLF"
			(at 270.51 195.58 0)
			(effects
				(font
					(size 1.27 1.27)
					(thickness 0.15)
				)
				(justify left bottom)
				(hide yes)
			)
		)
		(property "Manufacturer" "Bourns"
			(at 273.05 195.58 0)
			(effects
				(font
					(size 1.27 1.27)
					(thickness 0.15)
				)
				(justify left bottom)
				(hide yes)
			)
		)
		(property "License" "Apache-2.0"
			(at 275.59 195.58 0)
			(effects
				(font
					(size 1.27 1.27)
					(thickness 0.15)
				)
				(justify left bottom)
				(hide yes)
			)
		)
		(property "Author" "Antmicro"
			(at 278.13 195.58 0)
			(effects
				(font
					(size 1.27 1.27)
					(thickness 0.15)
				)
				(justify left bottom)
				(hide yes)
			)
		)
		(property "Val" "1k"
			(at 251.46 213.36 90)
			(effects
				(font
					(size 1.27 1.27)
					(thickness 0.15)
				)
				(justify right)
			)
		)
		(property "Tolerance" "1%"
			(at 260.35 195.58 0)
			(effects
				(font
					(size 1.27 1.27)
				)
				(justify left bottom)
				(hide yes)
			)
		)
		(property "Public" "False"
			(at 280.67 195.58 0)
			(effects
				(font
					(size 1.27 1.27)
				)
				(justify left bottom)
				(hide yes)
			)
		)
		(pin "2"
		)
		(pin "1"
		)
		(instances
			(project "com-express-7-baseboard"
				(path ""
					(reference "R170")
					(unit 1)
				)
			)
		)
	)
	(symbol
		(lib_id "antmicropower:GND")
		(at 285.75 134.62 0)
		(unit 1)
		(exclude_from_sim no)
		(in_bom yes)
		(on_board yes)
		(dnp no)
		(property "Reference" "#PWR0252"
			(at 294.64 137.16 0)
			(effects
				(font
					(size 1.27 1.27)
					(thickness 0.15)
				)
				(justify left bottom)
				(hide yes)
			)
		)
		(property "Value" "GND"
			(at 285.75 138.43 0)
			(effects
				(font
					(size 1.27 1.27)
					(thickness 0.15)
				)
			)
		)
		(property "Footprint" ""
			(at 294.64 142.24 0)
			(effects
				(font
					(size 1.27 1.27)
					(thickness 0.15)
				)
				(justify left bottom)
				(hide yes)
			)
		)
		(property "Datasheet" ""
			(at 294.64 147.32 0)
			(effects
				(font
					(size 1.27 1.27)
					(thickness 0.15)
				)
				(justify left bottom)
				(hide yes)
			)
		)
		(property "Description" ""
			(at 285.75 134.62 0)
			(effects
				(font
					(size 1.27 1.27)
				)
				(hide yes)
			)
		)
		(property "Author" "Antmicro"
			(at 294.64 142.24 0)
			(effects
				(font
					(size 1.27 1.27)
					(thickness 0.15)
				)
				(justify left bottom)
				(hide yes)
			)
		)
		(property "License" "Apache-2.0"
			(at 294.64 144.78 0)
			(effects
				(font
					(size 1.27 1.27)
					(thickness 0.15)
				)
				(justify left bottom)
				(hide yes)
			)
		)
		(pin "1"
		)
		(instances
			(project "com-express-7-baseboard"
				(path ""
					(reference "#PWR0252")
					(unit 1)
				)
			)
		)
	)
	(symbol
		(lib_id "antmicropower:GND")
		(at 302.26 78.74 0)
		(unit 1)
		(exclude_from_sim no)
		(in_bom yes)
		(on_board yes)
		(dnp no)
		(property "Reference" "#PWR0259"
			(at 311.15 81.28 0)
			(effects
				(font
					(size 1.27 1.27)
					(thickness 0.15)
				)
				(justify left bottom)
				(hide yes)
			)
		)
		(property "Value" "GND"
			(at 302.26 82.55 0)
			(effects
				(font
					(size 1.27 1.27)
					(thickness 0.15)
				)
			)
		)
		(property "Footprint" ""
			(at 311.15 86.36 0)
			(effects
				(font
					(size 1.27 1.27)
					(thickness 0.15)
				)
				(justify left bottom)
				(hide yes)
			)
		)
		(property "Datasheet" ""
			(at 311.15 91.44 0)
			(effects
				(font
					(size 1.27 1.27)
					(thickness 0.15)
				)
				(justify left bottom)
				(hide yes)
			)
		)
		(property "Description" ""
			(at 302.26 78.74 0)
			(effects
				(font
					(size 1.27 1.27)
				)
				(hide yes)
			)
		)
		(property "Author" "Antmicro"
			(at 311.15 86.36 0)
			(effects
				(font
					(size 1.27 1.27)
					(thickness 0.15)
				)
				(justify left bottom)
				(hide yes)
			)
		)
		(property "License" "Apache-2.0"
			(at 311.15 88.9 0)
			(effects
				(font
					(size 1.27 1.27)
					(thickness 0.15)
				)
				(justify left bottom)
				(hide yes)
			)
		)
		(pin "1"
		)
		(instances
			(project "com-express-7-baseboard"
				(path ""
					(reference "#PWR0259")
					(unit 1)
				)
			)
		)
	)
	(symbol
		(lib_id "antmicroTestPoints:TP_0.75mm_SMD")
		(at 76.2 129.54 0)
		(unit 1)
		(exclude_from_sim no)
		(in_bom no)
		(on_board yes)
		(dnp no)
		(fields_autoplaced yes)
		(property "Reference" "TP31"
			(at 81.28 129.54 0)
			(effects
				(font
					(size 1.27 1.27)
					(thickness 0.15)
				)
				(justify left)
			)
		)
		(property "Value" "TP_0.75mm_SMD"
			(at 86.995 133.35 0)
			(effects
				(font
					(size 1.27 1.27)
					(thickness 0.15)
				)
				(justify left bottom)
				(hide yes)
			)
		)
		(property "Footprint" "antmicro-footprints:TP_SMD_0.75mm"
			(at 86.995 135.89 0)
			(effects
				(font
					(size 1.27 1.27)
					(thickness 0.15)
				)
				(justify left bottom)
				(hide yes)
			)
		)
		(property "Datasheet" ""
			(at 93.98 142.24 0)
			(effects
				(font
					(size 1.27 1.27)
					(thickness 0.15)
				)
				(justify left bottom)
				(hide yes)
			)
		)
		(property "Description" ""
			(at 76.2 129.54 0)
			(effects
				(font
					(size 1.27 1.27)
				)
				(hide yes)
			)
		)
		(property "MPN" ""
			(at 86.995 140.97 0)
			(effects
				(font
					(size 1.27 1.27)
					(thickness 0.15)
				)
				(justify left bottom)
				(hide yes)
			)
		)
		(property "Manufacturer" ""
			(at 86.995 135.89 0)
			(effects
				(font
					(size 1.27 1.27)
					(thickness 0.15)
				)
				(justify left bottom)
				(hide yes)
			)
		)
		(property "Author" "Antmicro"
			(at 86.995 138.43 0)
			(effects
				(font
					(size 1.27 1.27)
					(thickness 0.15)
				)
				(justify left bottom)
				(hide yes)
			)
		)
		(property "License" "Apache-2.0"
			(at 86.995 140.97 0)
			(effects
				(font
					(size 1.27 1.27)
					(thickness 0.15)
				)
				(justify left bottom)
				(hide yes)
			)
		)
		(property "Public" "False"
			(at 86.36 143.51 0)
			(effects
				(font
					(size 1.27 1.27)
				)
				(justify left bottom)
				(hide yes)
			)
		)
		(pin "1"
		)
		(instances
			(project "com-express-7-baseboard"
				(path ""
					(reference "TP31")
					(unit 1)
				)
			)
		)
	)
	(symbol
		(lib_id "antmicroDiodesRectifiersSingle:BAT54C")
		(at 269.24 140.97 0)
		(unit 1)
		(exclude_from_sim no)
		(in_bom yes)
		(on_board yes)
		(dnp no)
		(fields_autoplaced yes)
		(property "Reference" "D20"
			(at 275.59 134.62 0)
			(effects
				(font
					(size 1.27 1.27)
					(thickness 0.15)
				)
			)
		)
		(property "Value" "BAT54C"
			(at 292.1 149.86 0)
			(effects
				(font
					(size 1.27 1.27)
					(thickness 0.15)
				)
				(justify left bottom)
				(hide yes)
			)
		)
		(property "Footprint" "antmicro-footprints:SOT-23-3"
			(at 292.1 152.4 0)
			(effects
				(font
					(size 1.27 1.27)
					(thickness 0.15)
				)
				(justify left bottom)
				(hide yes)
			)
		)
		(property "Datasheet" "https://diotec.com/request/datasheet/bat54.pdf"
			(at 292.1 154.94 0)
			(effects
				(font
					(size 1.27 1.27)
					(thickness 0.15)
				)
				(justify left bottom)
				(hide yes)
			)
		)
		(property "Description" ""
			(at 269.24 140.97 0)
			(effects
				(font
					(size 1.27 1.27)
				)
				(hide yes)
			)
		)
		(property "MPN" "BAT54C"
			(at 275.59 137.16 0)
			(effects
				(font
					(size 1.27 1.27)
					(thickness 0.15)
				)
			)
		)
		(property "Manufacturer" "Diotec Semiconductor"
			(at 292.1 157.48 0)
			(effects
				(font
					(size 1.27 1.27)
					(thickness 0.15)
				)
				(justify left bottom)
				(hide yes)
			)
		)
		(property "Author" "Antmicro"
			(at 292.1 160.02 0)
			(effects
				(font
					(size 1.27 1.27)
					(thickness 0.15)
				)
				(justify left bottom)
				(hide yes)
			)
		)
		(property "License" "Apache-2.0"
			(at 292.1 162.56 0)
			(effects
				(font
					(size 1.27 1.27)
					(thickness 0.15)
				)
				(justify left bottom)
				(hide yes)
			)
		)
		(pin "1"
		)
		(pin "3"
		)
		(pin "2"
		)
		(instances
			(project "com-express-7-baseboard"
				(path ""
					(reference "D20")
					(unit 1)
				)
			)
		)
	)
	(symbol
		(lib_id "antmicroTestPoints:TP_0.75mm_SMD")
		(at 76.2 119.38 0)
		(unit 1)
		(exclude_from_sim no)
		(in_bom no)
		(on_board yes)
		(dnp no)
		(fields_autoplaced yes)
		(property "Reference" "TP27"
			(at 81.28 119.38 0)
			(effects
				(font
					(size 1.27 1.27)
					(thickness 0.15)
				)
				(justify left)
			)
		)
		(property "Value" "TP_0.75mm_SMD"
			(at 86.995 123.19 0)
			(effects
				(font
					(size 1.27 1.27)
					(thickness 0.15)
				)
				(justify left bottom)
				(hide yes)
			)
		)
		(property "Footprint" "antmicro-footprints:TP_SMD_0.75mm"
			(at 86.995 125.73 0)
			(effects
				(font
					(size 1.27 1.27)
					(thickness 0.15)
				)
				(justify left bottom)
				(hide yes)
			)
		)
		(property "Datasheet" ""
			(at 93.98 132.08 0)
			(effects
				(font
					(size 1.27 1.27)
					(thickness 0.15)
				)
				(justify left bottom)
				(hide yes)
			)
		)
		(property "Description" ""
			(at 76.2 119.38 0)
			(effects
				(font
					(size 1.27 1.27)
				)
				(hide yes)
			)
		)
		(property "MPN" ""
			(at 86.995 130.81 0)
			(effects
				(font
					(size 1.27 1.27)
					(thickness 0.15)
				)
				(justify left bottom)
				(hide yes)
			)
		)
		(property "Manufacturer" ""
			(at 86.995 125.73 0)
			(effects
				(font
					(size 1.27 1.27)
					(thickness 0.15)
				)
				(justify left bottom)
				(hide yes)
			)
		)
		(property "Author" "Antmicro"
			(at 86.995 128.27 0)
			(effects
				(font
					(size 1.27 1.27)
					(thickness 0.15)
				)
				(justify left bottom)
				(hide yes)
			)
		)
		(property "License" "Apache-2.0"
			(at 86.995 130.81 0)
			(effects
				(font
					(size 1.27 1.27)
					(thickness 0.15)
				)
				(justify left bottom)
				(hide yes)
			)
		)
		(property "Public" "False"
			(at 86.36 133.35 0)
			(effects
				(font
					(size 1.27 1.27)
				)
				(justify left bottom)
				(hide yes)
			)
		)
		(pin "1"
		)
		(instances
			(project "com-express-7-baseboard"
				(path ""
					(reference "TP27")
					(unit 1)
				)
			)
		)
	)
	(symbol
		(lib_id "antmicropower:GND")
		(at 264.16 50.8 0)
		(unit 1)
		(exclude_from_sim no)
		(in_bom yes)
		(on_board yes)
		(dnp no)
		(property "Reference" "#PWR0258"
			(at 273.05 53.34 0)
			(effects
				(font
					(size 1.27 1.27)
					(thickness 0.15)
				)
				(justify left bottom)
				(hide yes)
			)
		)
		(property "Value" "GND"
			(at 264.16 54.61 0)
			(effects
				(font
					(size 1.27 1.27)
					(thickness 0.15)
				)
			)
		)
		(property "Footprint" ""
			(at 273.05 58.42 0)
			(effects
				(font
					(size 1.27 1.27)
					(thickness 0.15)
				)
				(justify left bottom)
				(hide yes)
			)
		)
		(property "Datasheet" ""
			(at 273.05 63.5 0)
			(effects
				(font
					(size 1.27 1.27)
					(thickness 0.15)
				)
				(justify left bottom)
				(hide yes)
			)
		)
		(property "Description" ""
			(at 264.16 50.8 0)
			(effects
				(font
					(size 1.27 1.27)
				)
				(hide yes)
			)
		)
		(property "Author" "Antmicro"
			(at 273.05 58.42 0)
			(effects
				(font
					(size 1.27 1.27)
					(thickness 0.15)
				)
				(justify left bottom)
				(hide yes)
			)
		)
		(property "License" "Apache-2.0"
			(at 273.05 60.96 0)
			(effects
				(font
					(size 1.27 1.27)
					(thickness 0.15)
				)
				(justify left bottom)
				(hide yes)
			)
		)
		(pin "1"
		)
		(instances
			(project "com-express-7-baseboard"
				(path ""
					(reference "#PWR0258")
					(unit 1)
				)
			)
		)
	)
	(symbol
		(lib_id "antmicroTransistorsFETsMOSFETsSingle:BSS138-7-F")
		(at 323.85 148.59 0)
		(unit 1)
		(exclude_from_sim no)
		(in_bom yes)
		(on_board yes)
		(dnp no)
		(fields_autoplaced yes)
		(property "Reference" "Q12"
			(at 335.28 144.78 0)
			(effects
				(font
					(size 1.27 1.27)
					(thickness 0.15)
				)
				(justify left)
			)
		)
		(property "Value" "BSS138-7-F"
			(at 335.28 147.32 0)
			(effects
				(font
					(size 1.27 1.27)
					(thickness 0.15)
				)
				(justify left)
				(hide yes)
			)
		)
		(property "Footprint" "antmicro-footprints:SOT-23-3"
			(at 346.71 156.21 0)
			(effects
				(font
					(size 1.27 1.27)
					(thickness 0.15)
				)
				(justify left bottom)
				(hide yes)
			)
		)
		(property "Datasheet" "https://www.diodes.com/assets/Datasheets/ds30144.pdf"
			(at 346.71 158.75 0)
			(effects
				(font
					(size 1.27 1.27)
					(thickness 0.15)
				)
				(justify left bottom)
				(hide yes)
			)
		)
		(property "Description" ""
			(at 323.85 148.59 0)
			(effects
				(font
					(size 1.27 1.27)
				)
				(hide yes)
			)
		)
		(property "MPN" "BSS138-7-F"
			(at 335.28 147.32 0)
			(effects
				(font
					(size 1.27 1.27)
					(thickness 0.15)
				)
				(justify left)
			)
		)
		(property "Manufacturer" "Diodes Incorporated"
			(at 346.71 163.83 0)
			(effects
				(font
					(size 1.27 1.27)
					(thickness 0.15)
				)
				(justify left bottom)
				(hide yes)
			)
		)
		(property "Author" "Antmicro"
			(at 346.71 166.37 0)
			(effects
				(font
					(size 1.27 1.27)
					(thickness 0.15)
				)
				(justify left bottom)
				(hide yes)
			)
		)
		(property "License" "Apache-2.0"
			(at 346.71 168.91 0)
			(effects
				(font
					(size 1.27 1.27)
					(thickness 0.15)
				)
				(justify left bottom)
				(hide yes)
			)
		)
		(pin "1"
		)
		(pin "2"
		)
		(pin "3"
		)
		(instances
			(project "com-express-7-baseboard"
				(path ""
					(reference "Q12")
					(unit 1)
				)
			)
		)
	)
	(symbol
		(lib_id "antmicroCapacitors0402:C_100n_0402")
		(at 382.27 212.09 90)
		(unit 1)
		(exclude_from_sim no)
		(in_bom yes)
		(on_board yes)
		(dnp no)
		(fields_autoplaced yes)
		(property "Reference" "C105"
			(at 384.81 208.2736 90)
			(effects
				(font
					(size 1.27 1.27)
					(thickness 0.15)
				)
				(justify right)
			)
		)
		(property "Value" "C_100n_0402"
			(at 392.43 191.77 0)
			(effects
				(font
					(size 1.27 1.27)
					(thickness 0.15)
				)
				(justify left bottom)
				(hide yes)
			)
		)
		(property "Footprint" "antmicro-footprints:C_0402_1005Metric"
			(at 394.97 191.77 0)
			(effects
				(font
					(size 1.27 1.27)
					(thickness 0.15)
				)
				(justify left bottom)
				(hide yes)
			)
		)
		(property "Datasheet" "https://www.murata.com/products/productdetail?partno=GRM155R61H104KE14%23"
			(at 397.51 191.77 0)
			(effects
				(font
					(size 1.27 1.27)
					(thickness 0.15)
				)
				(justify left bottom)
				(hide yes)
			)
		)
		(property "Description" ""
			(at 382.27 212.09 0)
			(effects
				(font
					(size 1.27 1.27)
				)
				(hide yes)
			)
		)
		(property "MPN" "GRM155R61H104KE14D"
			(at 400.05 191.77 0)
			(effects
				(font
					(size 1.27 1.27)
					(thickness 0.15)
				)
				(justify left bottom)
				(hide yes)
			)
		)
		(property "Manufacturer" "Murata"
			(at 402.59 191.77 0)
			(effects
				(font
					(size 1.27 1.27)
					(thickness 0.15)
				)
				(justify left bottom)
				(hide yes)
			)
		)
		(property "License" "Apache-2.0"
			(at 405.13 191.77 0)
			(effects
				(font
					(size 1.27 1.27)
					(thickness 0.15)
				)
				(justify left bottom)
				(hide yes)
			)
		)
		(property "Author" "Antmicro"
			(at 407.67 191.77 0)
			(effects
				(font
					(size 1.27 1.27)
					(thickness 0.15)
				)
				(justify left bottom)
				(hide yes)
			)
		)
		(property "Val" "100n"
			(at 384.81 210.8136 90)
			(effects
				(font
					(size 1.27 1.27)
					(thickness 0.15)
				)
				(justify right)
			)
		)
		(property "Voltage" "50V"
			(at 410.21 191.77 0)
			(effects
				(font
					(size 1.27 1.27)
				)
				(justify left bottom)
				(hide yes)
			)
		)
		(property "Dielectric" "X5R"
			(at 412.75 191.77 0)
			(effects
				(font
					(size 1.27 1.27)
				)
				(justify left bottom)
				(hide yes)
			)
		)
		(property "Public" "False"
			(at 415.29 191.77 0)
			(effects
				(font
					(size 1.27 1.27)
				)
				(justify left bottom)
				(hide yes)
			)
		)
		(pin "2"
		)
		(pin "1"
		)
		(instances
			(project "com-express-7-baseboard"
				(path ""
					(reference "C105")
					(unit 1)
				)
			)
		)
	)
	(symbol
		(lib_id "antmicroCapacitors0402:C_100n_0402")
		(at 116.84 128.27 90)
		(unit 1)
		(exclude_from_sim no)
		(in_bom yes)
		(on_board yes)
		(dnp no)
		(property "Reference" "C96"
			(at 110.49 124.46 90)
			(effects
				(font
					(size 1.27 1.27)
					(thickness 0.15)
				)
				(justify right)
			)
		)
		(property "Value" "C_100n_0402"
			(at 127 107.95 0)
			(effects
				(font
					(size 1.27 1.27)
					(thickness 0.15)
				)
				(justify left bottom)
				(hide yes)
			)
		)
		(property "Footprint" "antmicro-footprints:C_0402_1005Metric"
			(at 129.54 107.95 0)
			(effects
				(font
					(size 1.27 1.27)
					(thickness 0.15)
				)
				(justify left bottom)
				(hide yes)
			)
		)
		(property "Datasheet" "https://www.murata.com/products/productdetail?partno=GRM155R61H104KE14%23"
			(at 132.08 107.95 0)
			(effects
				(font
					(size 1.27 1.27)
					(thickness 0.15)
				)
				(justify left bottom)
				(hide yes)
			)
		)
		(property "Description" ""
			(at 116.84 128.27 0)
			(effects
				(font
					(size 1.27 1.27)
				)
				(hide yes)
			)
		)
		(property "MPN" "GRM155R61H104KE14D"
			(at 134.62 107.95 0)
			(effects
				(font
					(size 1.27 1.27)
					(thickness 0.15)
				)
				(justify left bottom)
				(hide yes)
			)
		)
		(property "Manufacturer" "Murata"
			(at 137.16 107.95 0)
			(effects
				(font
					(size 1.27 1.27)
					(thickness 0.15)
				)
				(justify left bottom)
				(hide yes)
			)
		)
		(property "License" "Apache-2.0"
			(at 139.7 107.95 0)
			(effects
				(font
					(size 1.27 1.27)
					(thickness 0.15)
				)
				(justify left bottom)
				(hide yes)
			)
		)
		(property "Author" "Antmicro"
			(at 142.24 107.95 0)
			(effects
				(font
					(size 1.27 1.27)
					(thickness 0.15)
				)
				(justify left bottom)
				(hide yes)
			)
		)
		(property "Val" "100n"
			(at 110.49 127 90)
			(effects
				(font
					(size 1.27 1.27)
					(thickness 0.15)
				)
				(justify right)
			)
		)
		(property "Voltage" "50V"
			(at 144.78 107.95 0)
			(effects
				(font
					(size 1.27 1.27)
				)
				(justify left bottom)
				(hide yes)
			)
		)
		(property "Dielectric" "X5R"
			(at 147.32 107.95 0)
			(effects
				(font
					(size 1.27 1.27)
				)
				(justify left bottom)
				(hide yes)
			)
		)
		(property "Public" "False"
			(at 149.86 107.95 0)
			(effects
				(font
					(size 1.27 1.27)
				)
				(justify left bottom)
				(hide yes)
			)
		)
		(pin "2"
		)
		(pin "1"
		)
		(instances
			(project "com-express-7-baseboard"
				(path ""
					(reference "C96")
					(unit 1)
				)
			)
		)
	)
	(symbol
		(lib_id "antmicroTestPoints:TP_0.75mm_SMD")
		(at 76.2 142.24 0)
		(unit 1)
		(exclude_from_sim no)
		(in_bom no)
		(on_board yes)
		(dnp no)
		(fields_autoplaced yes)
		(property "Reference" "TP33"
			(at 81.28 142.24 0)
			(effects
				(font
					(size 1.27 1.27)
					(thickness 0.15)
				)
				(justify left)
			)
		)
		(property "Value" "TP_0.75mm_SMD"
			(at 86.995 146.05 0)
			(effects
				(font
					(size 1.27 1.27)
					(thickness 0.15)
				)
				(justify left bottom)
				(hide yes)
			)
		)
		(property "Footprint" "antmicro-footprints:TP_SMD_0.75mm"
			(at 86.995 148.59 0)
			(effects
				(font
					(size 1.27 1.27)
					(thickness 0.15)
				)
				(justify left bottom)
				(hide yes)
			)
		)
		(property "Datasheet" ""
			(at 93.98 154.94 0)
			(effects
				(font
					(size 1.27 1.27)
					(thickness 0.15)
				)
				(justify left bottom)
				(hide yes)
			)
		)
		(property "Description" ""
			(at 76.2 142.24 0)
			(effects
				(font
					(size 1.27 1.27)
				)
				(hide yes)
			)
		)
		(property "MPN" ""
			(at 86.995 153.67 0)
			(effects
				(font
					(size 1.27 1.27)
					(thickness 0.15)
				)
				(justify left bottom)
				(hide yes)
			)
		)
		(property "Manufacturer" ""
			(at 86.995 148.59 0)
			(effects
				(font
					(size 1.27 1.27)
					(thickness 0.15)
				)
				(justify left bottom)
				(hide yes)
			)
		)
		(property "Author" "Antmicro"
			(at 86.995 151.13 0)
			(effects
				(font
					(size 1.27 1.27)
					(thickness 0.15)
				)
				(justify left bottom)
				(hide yes)
			)
		)
		(property "License" "Apache-2.0"
			(at 86.995 153.67 0)
			(effects
				(font
					(size 1.27 1.27)
					(thickness 0.15)
				)
				(justify left bottom)
				(hide yes)
			)
		)
		(property "Public" "False"
			(at 86.36 156.21 0)
			(effects
				(font
					(size 1.27 1.27)
				)
				(justify left bottom)
				(hide yes)
			)
		)
		(pin "1"
		)
		(instances
			(project "com-express-7-baseboard"
				(path ""
					(reference "TP33")
					(unit 1)
				)
			)
		)
	)
	(symbol
		(lib_id "antmicropower:+3V3")
		(at 91.44 182.88 0)
		(unit 1)
		(exclude_from_sim no)
		(in_bom yes)
		(on_board yes)
		(dnp no)
		(property "Reference" "#PWR0227"
			(at 106.68 182.88 0)
			(effects
				(font
					(size 1.27 1.27)
					(thickness 0.15)
				)
				(justify left bottom)
				(hide yes)
			)
		)
		(property "Value" "+3V3"
			(at 91.44 179.07 0)
			(effects
				(font
					(size 1.27 1.27)
					(thickness 0.15)
				)
			)
		)
		(property "Footprint" ""
			(at 106.68 190.5 0)
			(effects
				(font
					(size 1.27 1.27)
					(thickness 0.15)
				)
				(justify left bottom)
				(hide yes)
			)
		)
		(property "Datasheet" ""
			(at 106.68 193.04 0)
			(effects
				(font
					(size 1.27 1.27)
					(thickness 0.15)
				)
				(justify left bottom)
				(hide yes)
			)
		)
		(property "Description" ""
			(at 91.44 182.88 0)
			(effects
				(font
					(size 1.27 1.27)
				)
				(hide yes)
			)
		)
		(property "Author" "Antmicro"
			(at 106.68 185.42 0)
			(effects
				(font
					(size 1.27 1.27)
					(thickness 0.15)
				)
				(justify left bottom)
				(hide yes)
			)
		)
		(property "License" "Apache-2.0"
			(at 106.68 187.96 0)
			(effects
				(font
					(size 1.27 1.27)
					(thickness 0.15)
				)
				(justify left bottom)
				(hide yes)
			)
		)
		(pin "1"
		)
		(instances
			(project "com-express-7-baseboard"
				(path ""
					(reference "#PWR0227")
					(unit 1)
				)
			)
		)
	)
	(symbol
		(lib_id "antmicropower:GND")
		(at 228.6 118.11 0)
		(mirror y)
		(unit 1)
		(exclude_from_sim no)
		(in_bom yes)
		(on_board yes)
		(dnp no)
		(property "Reference" "#PWR0246"
			(at 219.71 120.65 0)
			(effects
				(font
					(size 1.27 1.27)
					(thickness 0.15)
				)
				(justify left bottom)
				(hide yes)
			)
		)
		(property "Value" "GND"
			(at 228.6 121.92 0)
			(effects
				(font
					(size 1.27 1.27)
					(thickness 0.15)
				)
			)
		)
		(property "Footprint" ""
			(at 219.71 125.73 0)
			(effects
				(font
					(size 1.27 1.27)
					(thickness 0.15)
				)
				(justify left bottom)
				(hide yes)
			)
		)
		(property "Datasheet" ""
			(at 219.71 130.81 0)
			(effects
				(font
					(size 1.27 1.27)
					(thickness 0.15)
				)
				(justify left bottom)
				(hide yes)
			)
		)
		(property "Description" ""
			(at 228.6 118.11 0)
			(effects
				(font
					(size 1.27 1.27)
				)
				(hide yes)
			)
		)
		(property "Author" "Antmicro"
			(at 219.71 125.73 0)
			(effects
				(font
					(size 1.27 1.27)
					(thickness 0.15)
				)
				(justify left bottom)
				(hide yes)
			)
		)
		(property "License" "Apache-2.0"
			(at 219.71 128.27 0)
			(effects
				(font
					(size 1.27 1.27)
					(thickness 0.15)
				)
				(justify left bottom)
				(hide yes)
			)
		)
		(pin "1"
		)
		(instances
			(project "com-express-7-baseboard"
				(path ""
					(reference "#PWR0246")
					(unit 1)
				)
			)
		)
	)
	(symbol
		(lib_id "antmicroB2BConnectors:Plug_Bus_CE7_EPT_401-51501-51")
		(at 76.2 238.76 0)
		(unit 3)
		(exclude_from_sim no)
		(in_bom yes)
		(on_board yes)
		(dnp no)
		(fields_autoplaced yes)
		(property "Reference" "J12"
			(at 57.15 231.14 0)
			(effects
				(font
					(size 1.27 1.27)
					(thickness 0.15)
				)
			)
		)
		(property "Value" "Plug_Bus_CE7_EPT_401-51501-51"
			(at 129.54 251.46 0)
			(effects
				(font
					(size 1.27 1.27)
					(thickness 0.15)
				)
				(justify left bottom)
				(hide yes)
			)
		)
		(property "Footprint" "antmicro-footprints:EPT_401-51501-51"
			(at 129.54 254 0)
			(effects
				(font
					(size 1.27 1.27)
					(thickness 0.15)
				)
				(justify left bottom)
				(hide yes)
			)
		)
		(property "Datasheet" "https://www.farnell.com/datasheets/1905093.pdf"
			(at 129.54 256.54 0)
			(effects
				(font
					(size 1.27 1.27)
					(thickness 0.15)
				)
				(justify left bottom)
				(hide yes)
			)
		)
		(property "Description" ""
			(at 76.2 238.76 0)
			(effects
				(font
					(size 1.27 1.27)
				)
				(hide yes)
			)
		)
		(property "Author" "Antmicro"
			(at 129.54 259.08 0)
			(effects
				(font
					(size 1.27 1.27)
					(thickness 0.15)
				)
				(justify left bottom)
				(hide yes)
			)
		)
		(property "License" "Apache-2.0"
			(at 129.54 261.62 0)
			(effects
				(font
					(size 1.27 1.27)
					(thickness 0.15)
				)
				(justify left bottom)
				(hide yes)
			)
		)
		(property "Manufacturer" "ept"
			(at 129.54 243.84 0)
			(effects
				(font
					(size 1.27 1.27)
					(thickness 0.15)
				)
				(justify left bottom)
				(hide yes)
			)
		)
		(property "MPN" "401-51501-51"
			(at 57.15 233.68 0)
			(effects
				(font
					(size 1.27 1.27)
					(thickness 0.15)
				)
			)
		)
		(pin "C91"
		)
		(pin "C92"
		)
		(pin "A15"
		)
		(pin "A91"
		)
		(pin "C34"
		)
		(pin "C35"
		)
		(pin "D22"
		)
		(pin "D23"
		)
		(pin "D55"
		)
		(pin "D56"
		)
		(pin "C55"
		)
		(pin "C56"
		)
		(pin "C71"
		)
		(pin "C72"
		)
		(pin "C32"
		)
		(pin "C33"
		)
		(pin "B6"
		)
		(pin "B58"
		)
		(pin "B59"
		)
		(pin "D5"
		)
		(pin "D51"
		)
		(pin "A29"
		)
		(pin "D46"
		)
		(pin "D47"
		)
		(pin "C105"
		)
		(pin "C106"
		)
		(pin "A16"
		)
		(pin "B22"
		)
		(pin "B51"
		)
		(pin "B30"
		)
		(pin "A44"
		)
		(pin "C51"
		)
		(pin "C60"
		)
		(pin "A81"
		)
		(pin "A82"
		)
		(pin "D90"
		)
		(pin "D93"
		)
		(pin "B68"
		)
		(pin "B69"
		)
		(pin "C103"
		)
		(pin "C104"
		)
		(pin "C58"
		)
		(pin "C59"
		)
		(pin "D84"
		)
		(pin "D87"
		)
		(pin "A30"
		)
		(pin "B29"
		)
		(pin "A41"
		)
		(pin "C40"
		)
		(pin "C42"
		)
		(pin "D80"
		)
		(pin "D83"
		)
		(pin "B103"
		)
		(pin "A102"
		)
		(pin "C101"
		)
		(pin "C102"
		)
		(pin "D11"
		)
		(pin "D110"
		)
		(pin "B37"
		)
		(pin "B45"
		)
		(pin "C61"
		)
		(pin "C62"
		)
		(pin "A42"
		)
		(pin "B36"
		)
		(pin "B57"
		)
		(pin "D12"
		)
		(pin "D44"
		)
		(pin "D48"
		)
		(pin "B32"
		)
		(pin "B107"
		)
		(pin "B108"
		)
		(pin "B110"
		)
		(pin "B101"
		)
		(pin "C63"
		)
		(pin "C64"
		)
		(pin "B50"
		)
		(pin "A87"
		)
		(pin "A86"
		)
		(pin "B27"
		)
		(pin "D17"
		)
		(pin "D24"
		)
		(pin "D26"
		)
		(pin "D27"
		)
		(pin "A47"
		)
		(pin "C81"
		)
		(pin "C82"
		)
		(pin "C68"
		)
		(pin "C69"
		)
		(pin "A74"
		)
		(pin "A48"
		)
		(pin "A57"
		)
		(pin "A43"
		)
		(pin "A31"
		)
		(pin "D29"
		)
		(pin "D30"
		)
		(pin "C36"
		)
		(pin "C37"
		)
		(pin "C3"
		)
		(pin "A35"
		)
		(pin "A34"
		)
		(pin "B7"
		)
		(pin "B46"
		)
		(pin "B1"
		)
		(pin "B63"
		)
		(pin "A51"
		)
		(pin "A99"
		)
		(pin "B17"
		)
		(pin "C13"
		)
		(pin "C4"
		)
		(pin "B102"
		)
		(pin "C38"
		)
		(pin "C39"
		)
		(pin "B3"
		)
		(pin "A90"
		)
		(pin "A72"
		)
		(pin "B84"
		)
		(pin "D19"
		)
		(pin "D20"
		)
		(pin "D43"
		)
		(pin "D45"
		)
		(pin "A77"
		)
		(pin "A78"
		)
		(pin "B38"
		)
		(pin "B86"
		)
		(pin "D77"
		)
		(pin "D8"
		)
		(pin "A32"
		)
		(pin "B85"
		)
		(pin "D73"
		)
		(pin "D76"
		)
		(pin "D63"
		)
		(pin "D64"
		)
		(pin "D67"
		)
		(pin "D70"
		)
		(pin "B83"
		)
		(pin "D81"
		)
		(pin "D82"
		)
		(pin "B41"
		)
		(pin "D49"
		)
		(pin "D50"
		)
		(pin "A75"
		)
		(pin "D2"
		)
		(pin "D21"
		)
		(pin "C78"
		)
		(pin "C79"
		)
		(pin "B19"
		)
		(pin "B39"
		)
		(pin "A12"
		)
		(pin "B66"
		)
		(pin "D4"
		)
		(pin "D85"
		)
		(pin "D86"
		)
		(pin "A105"
		)
		(pin "B90"
		)
		(pin "A22"
		)
		(pin "A109"
		)
		(pin "B88"
		)
		(pin "B14"
		)
		(pin "B71"
		)
		(pin "B52"
		)
		(pin "B53"
		)
		(pin "D7"
		)
		(pin "A108"
		)
		(pin "C85"
		)
		(pin "C86"
		)
		(pin "B61"
		)
		(pin "B62"
		)
		(pin "D68"
		)
		(pin "D69"
		)
		(pin "A88"
		)
		(pin "A89"
		)
		(pin "D6"
		)
		(pin "C7"
		)
		(pin "B33"
		)
		(pin "D88"
		)
		(pin "D89"
		)
		(pin "B26"
		)
		(pin "A76"
		)
		(pin "D101"
		)
		(pin "D102"
		)
		(pin "B12"
		)
		(pin "C15"
		)
		(pin "C16"
		)
		(pin "A18"
		)
		(pin "A13"
		)
		(pin "A66"
		)
		(pin "C26"
		)
		(pin "C27"
		)
		(pin "A101"
		)
		(pin "A17"
		)
		(pin "B96"
		)
		(pin "C22"
		)
		(pin "C23"
		)
		(pin "A79"
		)
		(pin "A54"
		)
		(pin "C41"
		)
		(pin "C44"
		)
		(pin "A100"
		)
		(pin "A67"
		)
		(pin "A10"
		)
		(pin "A14"
		)
		(pin "C6"
		)
		(pin "A84"
		)
		(pin "B91"
		)
		(pin "C29"
		)
		(pin "C30"
		)
		(pin "A37"
		)
		(pin "A39"
		)
		(pin "B10"
		)
		(pin "B34"
		)
		(pin "C54"
		)
		(pin "C57"
		)
		(pin "B64"
		)
		(pin "B65"
		)
		(pin "A58"
		)
		(pin "A59"
		)
		(pin "B92"
		)
		(pin "C43"
		)
		(pin "C45"
		)
		(pin "A97"
		)
		(pin "A11"
		)
		(pin "A61"
		)
		(pin "A62"
		)
		(pin "B48"
		)
		(pin "B54"
		)
		(pin "D71"
		)
		(pin "D72"
		)
		(pin "A26"
		)
		(pin "A36"
		)
		(pin "D31"
		)
		(pin "D36"
		)
		(pin "B76"
		)
		(pin "B21"
		)
		(pin "B24"
		)
		(pin "B94"
		)
		(pin "D3"
		)
		(pin "B79"
		)
		(pin "A85"
		)
		(pin "A23"
		)
		(pin "A25"
		)
		(pin "A24"
		)
		(pin "D14"
		)
		(pin "D18"
		)
		(pin "B15"
		)
		(pin "A107"
		)
		(pin "A98"
		)
		(pin "D9"
		)
		(pin "B44"
		)
		(pin "A4"
		)
		(pin "C28"
		)
		(pin "C31"
		)
		(pin "A9"
		)
		(pin "C49"
		)
		(pin "C50"
		)
		(pin "A83"
		)
		(pin "A110"
		)
		(pin "D52"
		)
		(pin "D53"
		)
		(pin "A40"
		)
		(pin "A71"
		)
		(pin "D98"
		)
		(pin "D99"
		)
		(pin "D40"
		)
		(pin "D42"
		)
		(pin "D37"
		)
		(pin "D41"
		)
		(pin "C109"
		)
		(pin "C11"
		)
		(pin "A106"
		)
		(pin "A3"
		)
		(pin "B109"
		)
		(pin "B40"
		)
		(pin "C70"
		)
		(pin "C73"
		)
		(pin "D13"
		)
		(pin "A1"
		)
		(pin "A46"
		)
		(pin "A20"
		)
		(pin "A104"
		)
		(pin "C9"
		)
		(pin "C110"
		)
		(pin "C14"
		)
		(pin "B23"
		)
		(pin "A93"
		)
		(pin "B89"
		)
		(pin "B87"
		)
		(pin "D54"
		)
		(pin "D60"
		)
		(pin "A21"
		)
		(pin "B93"
		)
		(pin "A70"
		)
		(pin "A60"
		)
		(pin "B97"
		)
		(pin "B95"
		)
		(pin "D38"
		)
		(pin "D39"
		)
		(pin "A50"
		)
		(pin "A52"
		)
		(pin "A53"
		)
		(pin "D91"
		)
		(pin "D92"
		)
		(pin "C67"
		)
		(pin "D57"
		)
		(pin "A96"
		)
		(pin "A92"
		)
		(pin "B70"
		)
		(pin "C46"
		)
		(pin "C47"
		)
		(pin "B4"
		)
		(pin "A64"
		)
		(pin "A65"
		)
		(pin "B43"
		)
		(pin "C21"
		)
		(pin "C25"
		)
		(pin "B42"
		)
		(pin "C19"
		)
		(pin "C20"
		)
		(pin "C18"
		)
		(pin "C2"
		)
		(pin "C107"
		)
		(pin "C108"
		)
		(pin "B35"
		)
		(pin "A28"
		)
		(pin "B11"
		)
		(pin "A103"
		)
		(pin "C97"
		)
		(pin "D1"
		)
		(pin "B98"
		)
		(pin "A19"
		)
		(pin "A68"
		)
		(pin "A69"
		)
		(pin "B55"
		)
		(pin "B56"
		)
		(pin "A8"
		)
		(pin "A33"
		)
		(pin "A95"
		)
		(pin "D96"
		)
		(pin "D97"
		)
		(pin "B31"
		)
		(pin "B105"
		)
		(pin "B100"
		)
		(pin "C65"
		)
		(pin "C66"
		)
		(pin "B104"
		)
		(pin "D61"
		)
		(pin "D62"
		)
		(pin "D78"
		)
		(pin "D79"
		)
		(pin "C83"
		)
		(pin "C84"
		)
		(pin "D74"
		)
		(pin "D75"
		)
		(pin "A45"
		)
		(pin "D106"
		)
		(pin "D107"
		)
		(pin "C8"
		)
		(pin "C80"
		)
		(pin "C87"
		)
		(pin "C90"
		)
		(pin "D58"
		)
		(pin "D59"
		)
		(pin "D104"
		)
		(pin "D105"
		)
		(pin "C93"
		)
		(pin "C96"
		)
		(pin "B73"
		)
		(pin "D108"
		)
		(pin "D109"
		)
		(pin "B20"
		)
		(pin "A27"
		)
		(pin "D34"
		)
		(pin "D35"
		)
		(pin "C17"
		)
		(pin "C24"
		)
		(pin "B49"
		)
		(pin "A6"
		)
		(pin "B5"
		)
		(pin "B99"
		)
		(pin "B25"
		)
		(pin "D94"
		)
		(pin "D95"
		)
		(pin "B106"
		)
		(pin "B67"
		)
		(pin "A2"
		)
		(pin "B13"
		)
		(pin "A49"
		)
		(pin "C52"
		)
		(pin "C53"
		)
		(pin "B72"
		)
		(pin "C94"
		)
		(pin "C95"
		)
		(pin "B74"
		)
		(pin "D10"
		)
		(pin "B75"
		)
		(pin "B77"
		)
		(pin "C98"
		)
		(pin "C99"
		)
		(pin "A7"
		)
		(pin "C88"
		)
		(pin "C89"
		)
		(pin "C10"
		)
		(pin "B78"
		)
		(pin "B81"
		)
		(pin "B28"
		)
		(pin "A63"
		)
		(pin "C76"
		)
		(pin "C77"
		)
		(pin "A55"
		)
		(pin "A56"
		)
		(pin "C48"
		)
		(pin "C5"
		)
		(pin "A5"
		)
		(pin "C1"
		)
		(pin "C100"
		)
		(pin "B47"
		)
		(pin "C74"
		)
		(pin "C75"
		)
		(pin "C12"
		)
		(pin "B80"
		)
		(pin "D15"
		)
		(pin "D16"
		)
		(pin "D100"
		)
		(pin "D103"
		)
		(pin "B2"
		)
		(pin "B9"
		)
		(pin "A94"
		)
		(pin "B82"
		)
		(pin "D25"
		)
		(pin "D28"
		)
		(pin "B16"
		)
		(pin "D65"
		)
		(pin "D66"
		)
		(pin "D32"
		)
		(pin "D33"
		)
		(pin "B8"
		)
		(pin "B60"
		)
		(pin "A38"
		)
		(pin "A73"
		)
		(pin "A80"
		)
		(pin "B18"
		)
		(pin "MP"
		)
		(instances
			(project "com-express-7-baseboard"
				(path ""
					(reference "J12")
					(unit 3)
				)
			)
		)
	)
	(symbol
		(lib_id "antmicroCapacitors0402:C_100n_0402")
		(at 264.16 50.8 90)
		(unit 1)
		(exclude_from_sim no)
		(in_bom yes)
		(on_board yes)
		(dnp no)
		(fields_autoplaced yes)
		(property "Reference" "C102"
			(at 266.7 46.9836 90)
			(effects
				(font
					(size 1.27 1.27)
					(thickness 0.15)
				)
				(justify right)
			)
		)
		(property "Value" "C_100n_0402"
			(at 274.32 30.48 0)
			(effects
				(font
					(size 1.27 1.27)
					(thickness 0.15)
				)
				(justify left bottom)
				(hide yes)
			)
		)
		(property "Footprint" "antmicro-footprints:C_0402_1005Metric"
			(at 276.86 30.48 0)
			(effects
				(font
					(size 1.27 1.27)
					(thickness 0.15)
				)
				(justify left bottom)
				(hide yes)
			)
		)
		(property "Datasheet" "https://www.murata.com/products/productdetail?partno=GRM155R61H104KE14%23"
			(at 279.4 30.48 0)
			(effects
				(font
					(size 1.27 1.27)
					(thickness 0.15)
				)
				(justify left bottom)
				(hide yes)
			)
		)
		(property "Description" ""
			(at 264.16 50.8 0)
			(effects
				(font
					(size 1.27 1.27)
				)
				(hide yes)
			)
		)
		(property "MPN" "GRM155R61H104KE14D"
			(at 281.94 30.48 0)
			(effects
				(font
					(size 1.27 1.27)
					(thickness 0.15)
				)
				(justify left bottom)
				(hide yes)
			)
		)
		(property "Manufacturer" "Murata"
			(at 284.48 30.48 0)
			(effects
				(font
					(size 1.27 1.27)
					(thickness 0.15)
				)
				(justify left bottom)
				(hide yes)
			)
		)
		(property "License" "Apache-2.0"
			(at 287.02 30.48 0)
			(effects
				(font
					(size 1.27 1.27)
					(thickness 0.15)
				)
				(justify left bottom)
				(hide yes)
			)
		)
		(property "Author" "Antmicro"
			(at 289.56 30.48 0)
			(effects
				(font
					(size 1.27 1.27)
					(thickness 0.15)
				)
				(justify left bottom)
				(hide yes)
			)
		)
		(property "Val" "100n"
			(at 266.7 49.5236 90)
			(effects
				(font
					(size 1.27 1.27)
					(thickness 0.15)
				)
				(justify right)
			)
		)
		(property "Voltage" "50V"
			(at 292.1 30.48 0)
			(effects
				(font
					(size 1.27 1.27)
				)
				(justify left bottom)
				(hide yes)
			)
		)
		(property "Dielectric" "X5R"
			(at 294.64 30.48 0)
			(effects
				(font
					(size 1.27 1.27)
				)
				(justify left bottom)
				(hide yes)
			)
		)
		(property "Public" "False"
			(at 297.18 30.48 0)
			(effects
				(font
					(size 1.27 1.27)
				)
				(justify left bottom)
				(hide yes)
			)
		)
		(pin "2"
		)
		(pin "1"
		)
		(instances
			(project "com-express-7-baseboard"
				(path ""
					(reference "C102")
					(unit 1)
				)
			)
		)
	)
	(symbol
		(lib_id "antmicroCapacitors0603:C_22u_16V_0603")
		(at 106.68 78.74 90)
		(unit 1)
		(exclude_from_sim no)
		(in_bom yes)
		(on_board yes)
		(dnp no)
		(fields_autoplaced yes)
		(property "Reference" "C95"
			(at 109.22 74.9236 90)
			(effects
				(font
					(size 1.27 1.27)
					(thickness 0.15)
				)
				(justify right)
			)
		)
		(property "Value" "C_22u_16V_0603"
			(at 116.84 58.42 0)
			(effects
				(font
					(size 1.27 1.27)
					(thickness 0.15)
				)
				(justify left bottom)
				(hide yes)
			)
		)
		(property "Footprint" "antmicro-footprints:C_0603_1608Metric"
			(at 119.38 58.42 0)
			(effects
				(font
					(size 1.27 1.27)
					(thickness 0.15)
				)
				(justify left bottom)
				(hide yes)
			)
		)
		(property "Datasheet" "https://product.samsungsem.com/mlcc/CL10A226MO7JZN.do"
			(at 121.92 58.42 0)
			(effects
				(font
					(size 1.27 1.27)
					(thickness 0.15)
				)
				(justify left bottom)
				(hide yes)
			)
		)
		(property "Description" ""
			(at 106.68 78.74 0)
			(effects
				(font
					(size 1.27 1.27)
				)
				(hide yes)
			)
		)
		(property "MPN" "CL10A226MO7JZNC"
			(at 124.46 58.42 0)
			(effects
				(font
					(size 1.27 1.27)
					(thickness 0.15)
				)
				(justify left bottom)
				(hide yes)
			)
		)
		(property "Manufacturer" "Samsung Electro-Mechanics"
			(at 127 58.42 0)
			(effects
				(font
					(size 1.27 1.27)
					(thickness 0.15)
				)
				(justify left bottom)
				(hide yes)
			)
		)
		(property "License" "Apache-2.0"
			(at 129.54 58.42 0)
			(effects
				(font
					(size 1.27 1.27)
					(thickness 0.15)
				)
				(justify left bottom)
				(hide yes)
			)
		)
		(property "Author" "Antmicro"
			(at 132.08 58.42 0)
			(effects
				(font
					(size 1.27 1.27)
					(thickness 0.15)
				)
				(justify left bottom)
				(hide yes)
			)
		)
		(property "Val" "22u"
			(at 109.22 77.4636 90)
			(effects
				(font
					(size 1.27 1.27)
					(thickness 0.15)
				)
				(justify right)
			)
		)
		(property "Voltage" "16V"
			(at 134.62 58.42 0)
			(effects
				(font
					(size 1.27 1.27)
				)
				(justify left bottom)
				(hide yes)
			)
		)
		(property "Dielectric" ""
			(at 137.16 58.42 0)
			(effects
				(font
					(size 1.27 1.27)
				)
				(justify left bottom)
				(hide yes)
			)
		)
		(property "Public" "False"
			(at 139.7 58.42 0)
			(effects
				(font
					(size 1.27 1.27)
				)
				(justify left bottom)
				(hide yes)
			)
		)
		(pin "1"
		)
		(pin "2"
		)
		(instances
			(project "com-express-7-baseboard"
				(path ""
					(reference "C95")
					(unit 1)
				)
			)
		)
	)
	(symbol
		(lib_id "antmicroTestPoints:TP_0.75mm_SMD")
		(at 76.2 190.5 0)
		(unit 1)
		(exclude_from_sim no)
		(in_bom no)
		(on_board yes)
		(dnp no)
		(fields_autoplaced yes)
		(property "Reference" "TP41"
			(at 81.28 190.5 0)
			(effects
				(font
					(size 1.27 1.27)
					(thickness 0.15)
				)
				(justify left)
			)
		)
		(property "Value" "TP_0.75mm_SMD"
			(at 86.995 194.31 0)
			(effects
				(font
					(size 1.27 1.27)
					(thickness 0.15)
				)
				(justify left bottom)
				(hide yes)
			)
		)
		(property "Footprint" "antmicro-footprints:TP_SMD_0.75mm"
			(at 86.995 196.85 0)
			(effects
				(font
					(size 1.27 1.27)
					(thickness 0.15)
				)
				(justify left bottom)
				(hide yes)
			)
		)
		(property "Datasheet" ""
			(at 93.98 203.2 0)
			(effects
				(font
					(size 1.27 1.27)
					(thickness 0.15)
				)
				(justify left bottom)
				(hide yes)
			)
		)
		(property "Description" ""
			(at 76.2 190.5 0)
			(effects
				(font
					(size 1.27 1.27)
				)
				(hide yes)
			)
		)
		(property "MPN" ""
			(at 86.995 201.93 0)
			(effects
				(font
					(size 1.27 1.27)
					(thickness 0.15)
				)
				(justify left bottom)
				(hide yes)
			)
		)
		(property "Manufacturer" ""
			(at 86.995 196.85 0)
			(effects
				(font
					(size 1.27 1.27)
					(thickness 0.15)
				)
				(justify left bottom)
				(hide yes)
			)
		)
		(property "Author" "Antmicro"
			(at 86.995 199.39 0)
			(effects
				(font
					(size 1.27 1.27)
					(thickness 0.15)
				)
				(justify left bottom)
				(hide yes)
			)
		)
		(property "License" "Apache-2.0"
			(at 86.995 201.93 0)
			(effects
				(font
					(size 1.27 1.27)
					(thickness 0.15)
				)
				(justify left bottom)
				(hide yes)
			)
		)
		(property "Public" "False"
			(at 86.36 204.47 0)
			(effects
				(font
					(size 1.27 1.27)
				)
				(justify left bottom)
				(hide yes)
			)
		)
		(pin "1"
		)
		(instances
			(project "com-express-7-baseboard"
				(path ""
					(reference "TP41")
					(unit 1)
				)
			)
		)
	)
	(symbol
		(lib_id "antmicroBatteryHoldersClipsContacts:Battery_Holder_MS621FE-FL11E")
		(at 116.84 71.12 0)
		(unit 1)
		(exclude_from_sim no)
		(in_bom yes)
		(on_board yes)
		(dnp no)
		(fields_autoplaced yes)
		(property "Reference" "BT1"
			(at 120.65 74.295 0)
			(effects
				(font
					(size 1.27 1.27)
					(thickness 0.15)
				)
				(justify left)
			)
		)
		(property "Value" "Battery_Holder_MS621FE-FL11E"
			(at 134.62 78.74 0)
			(effects
				(font
					(size 1.27 1.27)
					(thickness 0.15)
				)
				(justify left bottom)
				(hide yes)
			)
		)
		(property "Footprint" "antmicro-footprints:MS621FE-FL11E"
			(at 134.62 81.28 0)
			(effects
				(font
					(size 1.27 1.27)
					(thickness 0.15)
				)
				(justify left bottom)
				(hide yes)
			)
		)
		(property "Datasheet" "https://www.sii.co.jp/en/me/datasheets/ms-rechargeable/ms621fe/"
			(at 134.62 83.82 0)
			(effects
				(font
					(size 1.27 1.27)
					(thickness 0.15)
				)
				(justify left bottom)
				(hide yes)
			)
		)
		(property "Description" ""
			(at 116.84 71.12 0)
			(effects
				(font
					(size 1.27 1.27)
				)
				(hide yes)
			)
		)
		(property "Manufacturer" "Seiko Instruments"
			(at 134.62 86.36 0)
			(effects
				(font
					(size 1.27 1.27)
					(thickness 0.15)
				)
				(justify left bottom)
				(hide yes)
			)
		)
		(property "MPN" "MS621FE-FL11E"
			(at 120.65 76.835 0)
			(effects
				(font
					(size 1.27 1.27)
					(thickness 0.15)
				)
				(justify left)
			)
		)
		(property "Author" "Antmicro"
			(at 134.62 88.9 0)
			(effects
				(font
					(size 1.27 1.27)
					(thickness 0.15)
				)
				(justify left bottom)
				(hide yes)
			)
		)
		(property "License" "Apache-2.0"
			(at 134.62 91.44 0)
			(effects
				(font
					(size 1.27 1.27)
					(thickness 0.15)
				)
				(justify left bottom)
				(hide yes)
			)
		)
		(pin "2"
		)
		(pin "1"
		)
		(instances
			(project "com-express-7-baseboard"
				(path ""
					(reference "BT1")
					(unit 1)
				)
			)
		)
	)
	(symbol
		(lib_id "antmicroResistors0402:R_100k_0402")
		(at 113.03 146.05 90)
		(unit 1)
		(exclude_from_sim no)
		(in_bom yes)
		(on_board yes)
		(dnp no)
		(property "Reference" "R164"
			(at 114.3 142.24 90)
			(effects
				(font
					(size 1.27 1.27)
					(thickness 0.15)
				)
				(justify right)
			)
		)
		(property "Value" "R_100k_0402"
			(at 125.73 125.73 0)
			(effects
				(font
					(size 1.27 1.27)
					(thickness 0.15)
				)
				(justify left bottom)
				(hide yes)
			)
		)
		(property "Footprint" "antmicro-footprints:R_0402_1005Metric"
			(at 128.27 125.73 0)
			(effects
				(font
					(size 1.27 1.27)
					(thickness 0.15)
				)
				(justify left bottom)
				(hide yes)
			)
		)
		(property "Datasheet" "https://www.bourns.com/docs/product-datasheets/cr.pdf"
			(at 130.81 125.73 0)
			(effects
				(font
					(size 1.27 1.27)
					(thickness 0.15)
				)
				(justify left bottom)
				(hide yes)
			)
		)
		(property "Description" ""
			(at 113.03 146.05 0)
			(effects
				(font
					(size 1.27 1.27)
				)
				(hide yes)
			)
		)
		(property "MPN" "CR0402-FX-1003GLF"
			(at 133.35 125.73 0)
			(effects
				(font
					(size 1.27 1.27)
					(thickness 0.15)
				)
				(justify left bottom)
				(hide yes)
			)
		)
		(property "Manufacturer" "Bourns"
			(at 135.89 125.73 0)
			(effects
				(font
					(size 1.27 1.27)
					(thickness 0.15)
				)
				(justify left bottom)
				(hide yes)
			)
		)
		(property "License" "Apache-2.0"
			(at 138.43 125.73 0)
			(effects
				(font
					(size 1.27 1.27)
					(thickness 0.15)
				)
				(justify left bottom)
				(hide yes)
			)
		)
		(property "Author" "Antmicro"
			(at 140.97 125.73 0)
			(effects
				(font
					(size 1.27 1.27)
					(thickness 0.15)
				)
				(justify left bottom)
				(hide yes)
			)
		)
		(property "Val" "100k"
			(at 114.3 144.78 90)
			(effects
				(font
					(size 1.27 1.27)
					(thickness 0.15)
				)
				(justify right)
			)
		)
		(property "Tolerance" "1%"
			(at 123.19 125.73 0)
			(effects
				(font
					(size 1.27 1.27)
				)
				(justify left bottom)
				(hide yes)
			)
		)
		(property "Public" "False"
			(at 143.51 125.73 0)
			(effects
				(font
					(size 1.27 1.27)
				)
				(justify left bottom)
				(hide yes)
			)
		)
		(pin "2"
		)
		(pin "1"
		)
		(instances
			(project "com-express-7-baseboard"
				(path ""
					(reference "R164")
					(unit 1)
				)
			)
		)
	)
	(symbol
		(lib_id "antmicropower:+12V")
		(at 104.14 36.83 0)
		(unit 1)
		(exclude_from_sim no)
		(in_bom yes)
		(on_board yes)
		(dnp no)
		(property "Reference" "#PWR0231"
			(at 104.14 40.64 0)
			(effects
				(font
					(size 1.27 1.27)
				)
				(hide yes)
			)
		)
		(property "Value" "+12V"
			(at 104.14 33.02 0)
			(effects
				(font
					(size 1.27 1.27)
				)
			)
		)
		(property "Footprint" ""
			(at 104.14 36.83 0)
			(effects
				(font
					(size 1.27 1.27)
				)
				(hide yes)
			)
		)
		(property "Datasheet" ""
			(at 104.14 36.83 0)
			(effects
				(font
					(size 1.27 1.27)
				)
				(hide yes)
			)
		)
		(property "Description" ""
			(at 104.14 36.83 0)
			(effects
				(font
					(size 1.27 1.27)
				)
				(hide yes)
			)
		)
		(pin "1"
		)
		(instances
			(project "com-express-7-baseboard"
				(path ""
					(reference "#PWR0231")
					(unit 1)
				)
			)
		)
	)
	(symbol
		(lib_id "antmicropower:GND")
		(at 337.82 78.74 0)
		(unit 1)
		(exclude_from_sim no)
		(in_bom yes)
		(on_board yes)
		(dnp no)
		(property "Reference" "#PWR0241"
			(at 346.71 81.28 0)
			(effects
				(font
					(size 1.27 1.27)
					(thickness 0.15)
				)
				(justify left bottom)
				(hide yes)
			)
		)
		(property "Value" "GND"
			(at 337.82 82.55 0)
			(effects
				(font
					(size 1.27 1.27)
					(thickness 0.15)
				)
			)
		)
		(property "Footprint" ""
			(at 346.71 86.36 0)
			(effects
				(font
					(size 1.27 1.27)
					(thickness 0.15)
				)
				(justify left bottom)
				(hide yes)
			)
		)
		(property "Datasheet" ""
			(at 346.71 91.44 0)
			(effects
				(font
					(size 1.27 1.27)
					(thickness 0.15)
				)
				(justify left bottom)
				(hide yes)
			)
		)
		(property "Description" ""
			(at 337.82 78.74 0)
			(effects
				(font
					(size 1.27 1.27)
				)
				(hide yes)
			)
		)
		(property "Author" "Antmicro"
			(at 346.71 86.36 0)
			(effects
				(font
					(size 1.27 1.27)
					(thickness 0.15)
				)
				(justify left bottom)
				(hide yes)
			)
		)
		(property "License" "Apache-2.0"
			(at 346.71 88.9 0)
			(effects
				(font
					(size 1.27 1.27)
					(thickness 0.15)
				)
				(justify left bottom)
				(hide yes)
			)
		)
		(pin "1"
		)
		(instances
			(project "com-express-7-baseboard"
				(path ""
					(reference "#PWR0241")
					(unit 1)
				)
			)
		)
	)
	(symbol
		(lib_id "antmicropower:GND")
		(at 88.9 83.82 0)
		(unit 1)
		(exclude_from_sim no)
		(in_bom yes)
		(on_board yes)
		(dnp no)
		(property "Reference" "#PWR0226"
			(at 88.9 90.17 0)
			(effects
				(font
					(size 1.27 1.27)
				)
				(hide yes)
			)
		)
		(property "Value" "GND"
			(at 88.9 87.63 0)
			(effects
				(font
					(size 1.27 1.27)
				)
			)
		)
		(property "Footprint" ""
			(at 88.9 83.82 0)
			(effects
				(font
					(size 1.27 1.27)
				)
				(hide yes)
			)
		)
		(property "Datasheet" ""
			(at 88.9 83.82 0)
			(effects
				(font
					(size 1.27 1.27)
				)
				(hide yes)
			)
		)
		(property "Description" ""
			(at 88.9 83.82 0)
			(effects
				(font
					(size 1.27 1.27)
				)
				(hide yes)
			)
		)
		(property "Author" "Antmicro"
			(at 97.79 91.44 0)
			(effects
				(font
					(size 1.27 1.27)
					(thickness 0.15)
				)
				(justify left bottom)
				(hide yes)
			)
		)
		(property "License" "Apache-2.0"
			(at 97.79 93.98 0)
			(effects
				(font
					(size 1.27 1.27)
					(thickness 0.15)
				)
				(justify left bottom)
				(hide yes)
			)
		)
		(pin "1"
		)
		(instances
			(project "com-express-7-baseboard"
				(path ""
					(reference "#PWR0226")
					(unit 1)
				)
			)
		)
	)
	(symbol
		(lib_id "antmicroCapacitorspol:C_Pol_68u_16V_Panasonic-TQC-D")
		(at 104.14 40.64 90)
		(mirror x)
		(unit 1)
		(exclude_from_sim no)
		(in_bom yes)
		(on_board yes)
		(dnp no)
		(fields_autoplaced yes)
		(property "Reference" "C94"
			(at 106.68 40.1066 90)
			(effects
				(font
					(size 1.27 1.27)
					(thickness 0.15)
				)
				(justify right)
			)
		)
		(property "Value" "C_Pol_68u_16V_Panasonic-TQC-D"
			(at 114.3 55.88 0)
			(effects
				(font
					(size 1.27 1.27)
					(thickness 0.15)
				)
				(justify left bottom)
				(hide yes)
			)
		)
		(property "Footprint" "antmicro-footprints:C_Pol_EIA-D"
			(at 116.84 55.88 0)
			(effects
				(font
					(size 1.27 1.27)
					(thickness 0.15)
				)
				(justify left bottom)
				(hide yes)
			)
		)
		(property "Datasheet" "https://industrial.panasonic.com/sa/products/pt/aluminum-cap-smd/models/16TQC68MYF"
			(at 119.38 55.88 0)
			(effects
				(font
					(size 1.27 1.27)
					(thickness 0.15)
				)
				(justify left bottom)
				(hide yes)
			)
		)
		(property "Description" ""
			(at 104.14 40.64 0)
			(effects
				(font
					(size 1.27 1.27)
				)
				(hide yes)
			)
		)
		(property "Author" "Antmicro"
			(at 121.92 55.88 0)
			(effects
				(font
					(size 1.27 1.27)
					(thickness 0.15)
				)
				(justify left bottom)
				(hide yes)
			)
		)
		(property "License" "Apache-2.0"
			(at 124.46 55.88 0)
			(effects
				(font
					(size 1.27 1.27)
					(thickness 0.15)
				)
				(justify left bottom)
				(hide yes)
			)
		)
		(property "MPN" "16TQC68MYF"
			(at 127 55.88 0)
			(effects
				(font
					(size 1.27 1.27)
					(thickness 0.15)
				)
				(justify left bottom)
				(hide yes)
			)
		)
		(property "Manufacturer" "Panasonic"
			(at 129.54 55.88 0)
			(effects
				(font
					(size 1.27 1.27)
					(thickness 0.15)
				)
				(justify left bottom)
				(hide yes)
			)
		)
		(property "Val" "68u"
			(at 106.68 42.6466 90)
			(effects
				(font
					(size 1.27 1.27)
					(thickness 0.15)
				)
				(justify right)
			)
		)
		(property "Voltage" "16V"
			(at 106.68 45.1866 90)
			(effects
				(font
					(size 1.27 1.27)
					(thickness 0.15)
				)
				(justify right)
			)
		)
		(property "Dielectric" "template_dielectric"
			(at 129.54 54.61 0)
			(effects
				(font
					(size 1.27 1.27)
				)
				(justify left bottom)
				(hide yes)
			)
		)
		(property "Public" "False"
			(at 132.08 54.61 0)
			(effects
				(font
					(size 1.27 1.27)
				)
				(justify left bottom)
				(hide yes)
			)
		)
		(pin "1"
		)
		(pin "2"
		)
		(instances
			(project "com-express-7-baseboard"
				(path ""
					(reference "C94")
					(unit 1)
				)
			)
		)
	)
	(symbol
		(lib_id "antmicroResistors0402:R_10k_0402")
		(at 270.51 66.04 90)
		(unit 1)
		(exclude_from_sim no)
		(in_bom yes)
		(on_board yes)
		(dnp yes)
		(property "Reference" "R175"
			(at 271.78 60.96 90)
			(effects
				(font
					(size 1.27 1.27)
					(thickness 0.15)
				)
				(justify right)
			)
		)
		(property "Value" "R_10k_0402"
			(at 283.21 45.72 0)
			(effects
				(font
					(size 1.27 1.27)
					(thickness 0.15)
				)
				(justify left bottom)
				(hide yes)
			)
		)
		(property "Footprint" "antmicro-footprints:R_0402_1005Metric"
			(at 285.75 45.72 0)
			(effects
				(font
					(size 1.27 1.27)
					(thickness 0.15)
				)
				(justify left bottom)
				(hide yes)
			)
		)
		(property "Datasheet" "https://www.bourns.com/docs/product-datasheets/cr.pdf"
			(at 288.29 45.72 0)
			(effects
				(font
					(size 1.27 1.27)
					(thickness 0.15)
				)
				(justify left bottom)
				(hide yes)
			)
		)
		(property "Description" ""
			(at 270.51 66.04 0)
			(effects
				(font
					(size 1.27 1.27)
				)
				(hide yes)
			)
		)
		(property "MPN" "CR0402-FX-1002GLF"
			(at 290.83 45.72 0)
			(effects
				(font
					(size 1.27 1.27)
					(thickness 0.15)
				)
				(justify left bottom)
				(hide yes)
			)
		)
		(property "Manufacturer" "Bourns"
			(at 293.37 45.72 0)
			(effects
				(font
					(size 1.27 1.27)
					(thickness 0.15)
				)
				(justify left bottom)
				(hide yes)
			)
		)
		(property "License" "Apache-2.0"
			(at 295.91 45.72 0)
			(effects
				(font
					(size 1.27 1.27)
					(thickness 0.15)
				)
				(justify left bottom)
				(hide yes)
			)
		)
		(property "Author" "Antmicro"
			(at 298.45 45.72 0)
			(effects
				(font
					(size 1.27 1.27)
					(thickness 0.15)
				)
				(justify left bottom)
				(hide yes)
			)
		)
		(property "Val" "10k"
			(at 271.78 63.5 90)
			(effects
				(font
					(size 1.27 1.27)
					(thickness 0.15)
				)
				(justify right)
			)
		)
		(property "Tolerance" "1%"
			(at 280.67 45.72 0)
			(effects
				(font
					(size 1.27 1.27)
				)
				(justify left bottom)
				(hide yes)
			)
		)
		(property "Public" "False"
			(at 300.99 45.72 0)
			(effects
				(font
					(size 1.27 1.27)
				)
				(justify left bottom)
				(hide yes)
			)
		)
		(pin "1"
		)
		(pin "2"
		)
		(instances
			(project "com-express-7-baseboard"
				(path ""
					(reference "R175")
					(unit 1)
				)
			)
		)
	)
	(symbol
		(lib_id "antmicropower:GND")
		(at 121.92 151.13 0)
		(unit 1)
		(exclude_from_sim no)
		(in_bom yes)
		(on_board yes)
		(dnp no)
		(property "Reference" "#PWR0239"
			(at 130.81 153.67 0)
			(effects
				(font
					(size 1.27 1.27)
					(thickness 0.15)
				)
				(justify left bottom)
				(hide yes)
			)
		)
		(property "Value" "GND"
			(at 121.92 154.94 0)
			(effects
				(font
					(size 1.27 1.27)
					(thickness 0.15)
				)
			)
		)
		(property "Footprint" ""
			(at 130.81 158.75 0)
			(effects
				(font
					(size 1.27 1.27)
					(thickness 0.15)
				)
				(justify left bottom)
				(hide yes)
			)
		)
		(property "Datasheet" ""
			(at 130.81 163.83 0)
			(effects
				(font
					(size 1.27 1.27)
					(thickness 0.15)
				)
				(justify left bottom)
				(hide yes)
			)
		)
		(property "Description" ""
			(at 121.92 151.13 0)
			(effects
				(font
					(size 1.27 1.27)
				)
				(hide yes)
			)
		)
		(property "Author" "Antmicro"
			(at 130.81 158.75 0)
			(effects
				(font
					(size 1.27 1.27)
					(thickness 0.15)
				)
				(justify left bottom)
				(hide yes)
			)
		)
		(property "License" "Apache-2.0"
			(at 130.81 161.29 0)
			(effects
				(font
					(size 1.27 1.27)
					(thickness 0.15)
				)
				(justify left bottom)
				(hide yes)
			)
		)
		(pin "1"
		)
		(instances
			(project "com-express-7-baseboard"
				(path ""
					(reference "#PWR0239")
					(unit 1)
				)
			)
		)
	)
	(symbol
		(lib_id "antmicroTestPoints:TP_0.75mm_SMD")
		(at 76.2 170.18 0)
		(unit 1)
		(exclude_from_sim no)
		(in_bom no)
		(on_board yes)
		(dnp no)
		(fields_autoplaced yes)
		(property "Reference" "TP36"
			(at 81.28 170.18 0)
			(effects
				(font
					(size 1.27 1.27)
					(thickness 0.15)
				)
				(justify left)
			)
		)
		(property "Value" "TP_0.75mm_SMD"
			(at 86.995 173.99 0)
			(effects
				(font
					(size 1.27 1.27)
					(thickness 0.15)
				)
				(justify left bottom)
				(hide yes)
			)
		)
		(property "Footprint" "antmicro-footprints:TP_SMD_0.75mm"
			(at 86.995 176.53 0)
			(effects
				(font
					(size 1.27 1.27)
					(thickness 0.15)
				)
				(justify left bottom)
				(hide yes)
			)
		)
		(property "Datasheet" ""
			(at 93.98 182.88 0)
			(effects
				(font
					(size 1.27 1.27)
					(thickness 0.15)
				)
				(justify left bottom)
				(hide yes)
			)
		)
		(property "Description" ""
			(at 76.2 170.18 0)
			(effects
				(font
					(size 1.27 1.27)
				)
				(hide yes)
			)
		)
		(property "MPN" ""
			(at 86.995 181.61 0)
			(effects
				(font
					(size 1.27 1.27)
					(thickness 0.15)
				)
				(justify left bottom)
				(hide yes)
			)
		)
		(property "Manufacturer" ""
			(at 86.995 176.53 0)
			(effects
				(font
					(size 1.27 1.27)
					(thickness 0.15)
				)
				(justify left bottom)
				(hide yes)
			)
		)
		(property "Author" "Antmicro"
			(at 86.995 179.07 0)
			(effects
				(font
					(size 1.27 1.27)
					(thickness 0.15)
				)
				(justify left bottom)
				(hide yes)
			)
		)
		(property "License" "Apache-2.0"
			(at 86.995 181.61 0)
			(effects
				(font
					(size 1.27 1.27)
					(thickness 0.15)
				)
				(justify left bottom)
				(hide yes)
			)
		)
		(property "Public" "False"
			(at 86.36 184.15 0)
			(effects
				(font
					(size 1.27 1.27)
				)
				(justify left bottom)
				(hide yes)
			)
		)
		(pin "1"
		)
		(instances
			(project "com-express-7-baseboard"
				(path ""
					(reference "TP36")
					(unit 1)
				)
			)
		)
	)
	(symbol
		(lib_id "antmicropower:+3V3_AON")
		(at 259.08 208.28 0)
		(mirror y)
		(unit 1)
		(exclude_from_sim no)
		(in_bom yes)
		(on_board yes)
		(dnp no)
		(property "Reference" "#PWR0253"
			(at 259.08 212.09 0)
			(effects
				(font
					(size 1.27 1.27)
				)
				(hide yes)
			)
		)
		(property "Value" "+3V3_AON"
			(at 259.08 204.47 0)
			(effects
				(font
					(size 1.27 1.27)
				)
			)
		)
		(property "Footprint" ""
			(at 259.08 208.28 0)
			(effects
				(font
					(size 1.27 1.27)
				)
				(hide yes)
			)
		)
		(property "Datasheet" ""
			(at 259.08 208.28 0)
			(effects
				(font
					(size 1.27 1.27)
				)
				(hide yes)
			)
		)
		(property "Description" ""
			(at 259.08 208.28 0)
			(effects
				(font
					(size 1.27 1.27)
				)
				(hide yes)
			)
		)
		(pin "1"
		)
		(instances
			(project "com-express-7-baseboard"
				(path ""
					(reference "#PWR0253")
					(unit 1)
				)
			)
		)
	)
	(symbol
		(lib_id "antmicropower:GND")
		(at 78.74 55.88 0)
		(unit 1)
		(exclude_from_sim no)
		(in_bom yes)
		(on_board yes)
		(dnp no)
		(property "Reference" "#PWR0224"
			(at 87.63 58.42 0)
			(effects
				(font
					(size 1.27 1.27)
					(thickness 0.15)
				)
				(justify left bottom)
				(hide yes)
			)
		)
		(property "Value" "GND"
			(at 78.74 59.69 0)
			(effects
				(font
					(size 1.27 1.27)
					(thickness 0.15)
				)
			)
		)
		(property "Footprint" ""
			(at 87.63 63.5 0)
			(effects
				(font
					(size 1.27 1.27)
					(thickness 0.15)
				)
				(justify left bottom)
				(hide yes)
			)
		)
		(property "Datasheet" ""
			(at 87.63 68.58 0)
			(effects
				(font
					(size 1.27 1.27)
					(thickness 0.15)
				)
				(justify left bottom)
				(hide yes)
			)
		)
		(property "Description" ""
			(at 78.74 55.88 0)
			(effects
				(font
					(size 1.27 1.27)
				)
				(hide yes)
			)
		)
		(property "Author" "Antmicro"
			(at 87.63 63.5 0)
			(effects
				(font
					(size 1.27 1.27)
					(thickness 0.15)
				)
				(justify left bottom)
				(hide yes)
			)
		)
		(property "License" "Apache-2.0"
			(at 87.63 66.04 0)
			(effects
				(font
					(size 1.27 1.27)
					(thickness 0.15)
				)
				(justify left bottom)
				(hide yes)
			)
		)
		(pin "1"
		)
		(instances
			(project "com-express-7-baseboard"
				(path ""
					(reference "#PWR0224")
					(unit 1)
				)
			)
		)
	)
	(symbol
		(lib_id "antmicroTVSDiodes:TPD2E2U06_SC70")
		(at 190.5 96.52 0)
		(unit 1)
		(exclude_from_sim no)
		(in_bom yes)
		(on_board yes)
		(dnp no)
		(fields_autoplaced yes)
		(property "Reference" "D6"
			(at 199.39 97.79 0)
			(effects
				(font
					(size 1.27 1.27)
					(thickness 0.15)
				)
				(justify left)
			)
		)
		(property "Value" "TPD2E2U06_SC70"
			(at 203.2 99.06 0)
			(effects
				(font
					(size 1.27 1.27)
					(thickness 0.15)
				)
				(justify left bottom)
				(hide yes)
			)
		)
		(property "Footprint" "antmicro-footprints:SC70-3"
			(at 203.2 101.6 0)
			(effects
				(font
					(size 1.27 1.27)
					(thickness 0.15)
				)
				(justify left bottom)
				(hide yes)
			)
		)
		(property "Datasheet" "https://www.ti.com/lit/ds/symlink/tpd2e2u06.pdf?ts=1706006131823&ref_url=https%253A%252F%252Fwww.ti.com%252Finterface%252Fdiodes%252Fesd-protection-diodes%252Fproducts.html"
			(at 203.2 104.14 0)
			(effects
				(font
					(size 1.27 1.27)
					(thickness 0.15)
				)
				(justify left bottom)
				(hide yes)
			)
		)
		(property "Description" ""
			(at 190.5 96.52 0)
			(effects
				(font
					(size 1.27 1.27)
				)
				(hide yes)
			)
		)
		(property "MPN" "TPD2E2U06DCKR"
			(at 199.39 100.33 0)
			(effects
				(font
					(size 1.27 1.27)
					(thickness 0.15)
				)
				(justify left)
			)
		)
		(property "Manufacturer" "Texas Instruments"
			(at 203.2 106.68 0)
			(effects
				(font
					(size 1.27 1.27)
					(thickness 0.15)
				)
				(justify left bottom)
				(hide yes)
			)
		)
		(property "Author" "Antmicro"
			(at 203.2 109.22 0)
			(effects
				(font
					(size 1.27 1.27)
					(thickness 0.15)
				)
				(justify left bottom)
				(hide yes)
			)
		)
		(property "License" "Apache-2.0"
			(at 203.2 111.76 0)
			(effects
				(font
					(size 1.27 1.27)
					(thickness 0.15)
				)
				(justify left bottom)
				(hide yes)
			)
		)
		(pin "1"
		)
		(pin "2"
		)
		(pin "3"
		)
		(instances
			(project "com-express-7-baseboard"
				(path ""
					(reference "D6")
					(unit 1)
				)
			)
		)
	)
	(symbol
		(lib_id "antmicroDiodesRectifiersSingle:BAT54C")
		(at 323.85 190.5 0)
		(unit 1)
		(exclude_from_sim no)
		(in_bom yes)
		(on_board yes)
		(dnp no)
		(fields_autoplaced yes)
		(property "Reference" "D21"
			(at 330.2 184.15 0)
			(effects
				(font
					(size 1.27 1.27)
					(thickness 0.15)
				)
			)
		)
		(property "Value" "BAT54C"
			(at 346.71 199.39 0)
			(effects
				(font
					(size 1.27 1.27)
					(thickness 0.15)
				)
				(justify left bottom)
				(hide yes)
			)
		)
		(property "Footprint" "antmicro-footprints:SOT-23-3"
			(at 346.71 201.93 0)
			(effects
				(font
					(size 1.27 1.27)
					(thickness 0.15)
				)
				(justify left bottom)
				(hide yes)
			)
		)
		(property "Datasheet" "https://diotec.com/request/datasheet/bat54.pdf"
			(at 346.71 204.47 0)
			(effects
				(font
					(size 1.27 1.27)
					(thickness 0.15)
				)
				(justify left bottom)
				(hide yes)
			)
		)
		(property "Description" ""
			(at 323.85 190.5 0)
			(effects
				(font
					(size 1.27 1.27)
				)
				(hide yes)
			)
		)
		(property "MPN" "BAT54C"
			(at 330.2 186.69 0)
			(effects
				(font
					(size 1.27 1.27)
					(thickness 0.15)
				)
			)
		)
		(property "Manufacturer" "Diotec Semiconductor"
			(at 346.71 207.01 0)
			(effects
				(font
					(size 1.27 1.27)
					(thickness 0.15)
				)
				(justify left bottom)
				(hide yes)
			)
		)
		(property "Author" "Antmicro"
			(at 346.71 209.55 0)
			(effects
				(font
					(size 1.27 1.27)
					(thickness 0.15)
				)
				(justify left bottom)
				(hide yes)
			)
		)
		(property "License" "Apache-2.0"
			(at 346.71 212.09 0)
			(effects
				(font
					(size 1.27 1.27)
					(thickness 0.15)
				)
				(justify left bottom)
				(hide yes)
			)
		)
		(pin "1"
		)
		(pin "3"
		)
		(pin "2"
		)
		(instances
			(project "com-express-7-baseboard"
				(path ""
					(reference "D21")
					(unit 1)
				)
			)
		)
	)
	(symbol
		(lib_id "antmicropower:GND")
		(at 284.48 158.75 0)
		(unit 1)
		(exclude_from_sim no)
		(in_bom yes)
		(on_board yes)
		(dnp no)
		(property "Reference" "#PWR0250"
			(at 293.37 161.29 0)
			(effects
				(font
					(size 1.27 1.27)
					(thickness 0.15)
				)
				(justify left bottom)
				(hide yes)
			)
		)
		(property "Value" "GND"
			(at 284.48 162.56 0)
			(effects
				(font
					(size 1.27 1.27)
					(thickness 0.15)
				)
			)
		)
		(property "Footprint" ""
			(at 293.37 166.37 0)
			(effects
				(font
					(size 1.27 1.27)
					(thickness 0.15)
				)
				(justify left bottom)
				(hide yes)
			)
		)
		(property "Datasheet" ""
			(at 293.37 171.45 0)
			(effects
				(font
					(size 1.27 1.27)
					(thickness 0.15)
				)
				(justify left bottom)
				(hide yes)
			)
		)
		(property "Description" ""
			(at 284.48 158.75 0)
			(effects
				(font
					(size 1.27 1.27)
				)
				(hide yes)
			)
		)
		(property "Author" "Antmicro"
			(at 293.37 166.37 0)
			(effects
				(font
					(size 1.27 1.27)
					(thickness 0.15)
				)
				(justify left bottom)
				(hide yes)
			)
		)
		(property "License" "Apache-2.0"
			(at 293.37 168.91 0)
			(effects
				(font
					(size 1.27 1.27)
					(thickness 0.15)
				)
				(justify left bottom)
				(hide yes)
			)
		)
		(pin "1"
		)
		(instances
			(project "com-express-7-baseboard"
				(path ""
					(reference "#PWR0250")
					(unit 1)
				)
			)
		)
	)
	(symbol
		(lib_id "antmicroCapacitors0402:C_1u_25V_0402")
		(at 228.6 115.57 90)
		(unit 1)
		(exclude_from_sim no)
		(in_bom yes)
		(on_board yes)
		(dnp no)
		(fields_autoplaced yes)
		(property "Reference" "C98"
			(at 231.14 111.7536 90)
			(effects
				(font
					(size 1.27 1.27)
					(thickness 0.15)
				)
				(justify right)
			)
		)
		(property "Value" "C_1u_25V_0402"
			(at 238.76 95.25 0)
			(effects
				(font
					(size 1.27 1.27)
					(thickness 0.15)
				)
				(justify left bottom)
				(hide yes)
			)
		)
		(property "Footprint" "antmicro-footprints:C_0402_1005Metric"
			(at 241.3 95.25 0)
			(effects
				(font
					(size 1.27 1.27)
					(thickness 0.15)
				)
				(justify left bottom)
				(hide yes)
			)
		)
		(property "Datasheet" "https://www.murata.com/products/productdetail?partno=GRM155R61E105KE11%23"
			(at 243.84 95.25 0)
			(effects
				(font
					(size 1.27 1.27)
					(thickness 0.15)
				)
				(justify left bottom)
				(hide yes)
			)
		)
		(property "Description" "SMD Multilayer Ceramic Capacitor, 1 µF, 25 V, 0402 [1005 Metric], ± 10%, X5R, GRM Series"
			(at 228.6 115.57 0)
			(effects
				(font
					(size 1.27 1.27)
				)
				(hide yes)
			)
		)
		(property "MPN" "GRM155R61E105KE11J"
			(at 246.38 95.25 0)
			(effects
				(font
					(size 1.27 1.27)
					(thickness 0.15)
				)
				(justify left bottom)
				(hide yes)
			)
		)
		(property "Manufacturer" "Murata"
			(at 248.92 95.25 0)
			(effects
				(font
					(size 1.27 1.27)
					(thickness 0.15)
				)
				(justify left bottom)
				(hide yes)
			)
		)
		(property "License" "Apache-2.0"
			(at 251.46 95.25 0)
			(effects
				(font
					(size 1.27 1.27)
					(thickness 0.15)
				)
				(justify left bottom)
				(hide yes)
			)
		)
		(property "Author" "Antmicro"
			(at 254 95.25 0)
			(effects
				(font
					(size 1.27 1.27)
					(thickness 0.15)
				)
				(justify left bottom)
				(hide yes)
			)
		)
		(property "Val" "1u"
			(at 231.14 114.2936 90)
			(effects
				(font
					(size 1.27 1.27)
					(thickness 0.15)
				)
				(justify right)
			)
		)
		(property "Voltage" "25V"
			(at 256.54 95.25 0)
			(effects
				(font
					(size 1.27 1.27)
				)
				(justify left bottom)
				(hide yes)
			)
		)
		(property "Dielectric" "X5R"
			(at 259.08 95.25 0)
			(effects
				(font
					(size 1.27 1.27)
				)
				(justify left bottom)
				(hide yes)
			)
		)
		(pin "2"
		)
		(pin "1"
		)
		(instances
			(project "com-express-7-baseboard"
				(path ""
					(reference "C98")
					(unit 1)
				)
			)
		)
	)
	(symbol
		(lib_id "antmicropower:GND")
		(at 106.68 83.82 0)
		(unit 1)
		(exclude_from_sim no)
		(in_bom yes)
		(on_board yes)
		(dnp no)
		(property "Reference" "#PWR0234"
			(at 106.68 90.17 0)
			(effects
				(font
					(size 1.27 1.27)
				)
				(hide yes)
			)
		)
		(property "Value" "GND"
			(at 106.68 87.63 0)
			(effects
				(font
					(size 1.27 1.27)
				)
			)
		)
		(property "Footprint" ""
			(at 106.68 83.82 0)
			(effects
				(font
					(size 1.27 1.27)
				)
				(hide yes)
			)
		)
		(property "Datasheet" ""
			(at 106.68 83.82 0)
			(effects
				(font
					(size 1.27 1.27)
				)
				(hide yes)
			)
		)
		(property "Description" ""
			(at 106.68 83.82 0)
			(effects
				(font
					(size 1.27 1.27)
				)
				(hide yes)
			)
		)
		(property "Author" "Antmicro"
			(at 115.57 91.44 0)
			(effects
				(font
					(size 1.27 1.27)
					(thickness 0.15)
				)
				(justify left bottom)
				(hide yes)
			)
		)
		(property "License" "Apache-2.0"
			(at 115.57 93.98 0)
			(effects
				(font
					(size 1.27 1.27)
					(thickness 0.15)
				)
				(justify left bottom)
				(hide yes)
			)
		)
		(pin "1"
		)
		(instances
			(project "com-express-7-baseboard"
				(path ""
					(reference "#PWR0234")
					(unit 1)
				)
			)
		)
	)
	(symbol
		(lib_id "antmicropower:GND")
		(at 293.37 158.75 0)
		(unit 1)
		(exclude_from_sim no)
		(in_bom yes)
		(on_board yes)
		(dnp no)
		(property "Reference" "#PWR0256"
			(at 302.26 161.29 0)
			(effects
				(font
					(size 1.27 1.27)
					(thickness 0.15)
				)
				(justify left bottom)
				(hide yes)
			)
		)
		(property "Value" "GND"
			(at 293.37 162.56 0)
			(effects
				(font
					(size 1.27 1.27)
					(thickness 0.15)
				)
			)
		)
		(property "Footprint" ""
			(at 302.26 166.37 0)
			(effects
				(font
					(size 1.27 1.27)
					(thickness 0.15)
				)
				(justify left bottom)
				(hide yes)
			)
		)
		(property "Datasheet" ""
			(at 302.26 171.45 0)
			(effects
				(font
					(size 1.27 1.27)
					(thickness 0.15)
				)
				(justify left bottom)
				(hide yes)
			)
		)
		(property "Description" ""
			(at 293.37 158.75 0)
			(effects
				(font
					(size 1.27 1.27)
				)
				(hide yes)
			)
		)
		(property "Author" "Antmicro"
			(at 302.26 166.37 0)
			(effects
				(font
					(size 1.27 1.27)
					(thickness 0.15)
				)
				(justify left bottom)
				(hide yes)
			)
		)
		(property "License" "Apache-2.0"
			(at 302.26 168.91 0)
			(effects
				(font
					(size 1.27 1.27)
					(thickness 0.15)
				)
				(justify left bottom)
				(hide yes)
			)
		)
		(pin "1"
		)
		(instances
			(project "com-express-7-baseboard"
				(path ""
					(reference "#PWR0256")
					(unit 1)
				)
			)
		)
	)
	(symbol
		(lib_id "antmicroResistors0402:R_2k2_0402")
		(at 88.9 66.04 90)
		(unit 1)
		(exclude_from_sim no)
		(in_bom yes)
		(on_board yes)
		(dnp no)
		(property "Reference" "R159"
			(at 87.63 62.23 90)
			(effects
				(font
					(size 1.27 1.27)
					(thickness 0.15)
				)
				(justify left)
			)
		)
		(property "Value" "R_2k2_0402"
			(at 101.6 45.72 0)
			(effects
				(font
					(size 1.27 1.27)
					(thickness 0.15)
				)
				(justify left bottom)
				(hide yes)
			)
		)
		(property "Footprint" "antmicro-footprints:R_0402_1005Metric"
			(at 104.14 45.72 0)
			(effects
				(font
					(size 1.27 1.27)
					(thickness 0.15)
				)
				(justify left bottom)
				(hide yes)
			)
		)
		(property "Datasheet" "https://www.bourns.com/docs/product-datasheets/cr.pdf"
			(at 106.68 45.72 0)
			(effects
				(font
					(size 1.27 1.27)
					(thickness 0.15)
				)
				(justify left bottom)
				(hide yes)
			)
		)
		(property "Description" ""
			(at 88.9 66.04 0)
			(effects
				(font
					(size 1.27 1.27)
				)
				(hide yes)
			)
		)
		(property "MPN" "CR0402-FX-2201GLF"
			(at 109.22 45.72 0)
			(effects
				(font
					(size 1.27 1.27)
					(thickness 0.15)
				)
				(justify left bottom)
				(hide yes)
			)
		)
		(property "Manufacturer" "Bourns"
			(at 111.76 45.72 0)
			(effects
				(font
					(size 1.27 1.27)
					(thickness 0.15)
				)
				(justify left bottom)
				(hide yes)
			)
		)
		(property "License" "Apache-2.0"
			(at 114.3 45.72 0)
			(effects
				(font
					(size 1.27 1.27)
					(thickness 0.15)
				)
				(justify left bottom)
				(hide yes)
			)
		)
		(property "Author" "Antmicro"
			(at 116.84 45.72 0)
			(effects
				(font
					(size 1.27 1.27)
					(thickness 0.15)
				)
				(justify left bottom)
				(hide yes)
			)
		)
		(property "Val" "2k2"
			(at 87.63 64.77 90)
			(effects
				(font
					(size 1.27 1.27)
					(thickness 0.15)
				)
				(justify left)
			)
		)
		(property "Tolerance" "1%"
			(at 99.06 45.72 0)
			(effects
				(font
					(size 1.27 1.27)
				)
				(justify left bottom)
				(hide yes)
			)
		)
		(property "Public" "False"
			(at 119.38 45.72 0)
			(effects
				(font
					(size 1.27 1.27)
				)
				(justify left bottom)
				(hide yes)
			)
		)
		(pin "1"
		)
		(pin "2"
		)
		(instances
			(project "com-express-7-baseboard"
				(path ""
					(reference "R159")
					(unit 1)
				)
			)
		)
	)
	(symbol
		(lib_id "antmicropower:GND")
		(at 113.03 146.05 0)
		(unit 1)
		(exclude_from_sim no)
		(in_bom yes)
		(on_board yes)
		(dnp no)
		(property "Reference" "#PWR0235"
			(at 121.92 148.59 0)
			(effects
				(font
					(size 1.27 1.27)
					(thickness 0.15)
				)
				(justify left bottom)
				(hide yes)
			)
		)
		(property "Value" "GND"
			(at 113.03 149.86 0)
			(effects
				(font
					(size 1.27 1.27)
					(thickness 0.15)
				)
			)
		)
		(property "Footprint" ""
			(at 121.92 153.67 0)
			(effects
				(font
					(size 1.27 1.27)
					(thickness 0.15)
				)
				(justify left bottom)
				(hide yes)
			)
		)
		(property "Datasheet" ""
			(at 121.92 158.75 0)
			(effects
				(font
					(size 1.27 1.27)
					(thickness 0.15)
				)
				(justify left bottom)
				(hide yes)
			)
		)
		(property "Description" ""
			(at 113.03 146.05 0)
			(effects
				(font
					(size 1.27 1.27)
				)
				(hide yes)
			)
		)
		(property "Author" "Antmicro"
			(at 121.92 153.67 0)
			(effects
				(font
					(size 1.27 1.27)
					(thickness 0.15)
				)
				(justify left bottom)
				(hide yes)
			)
		)
		(property "License" "Apache-2.0"
			(at 121.92 156.21 0)
			(effects
				(font
					(size 1.27 1.27)
					(thickness 0.15)
				)
				(justify left bottom)
				(hide yes)
			)
		)
		(pin "1"
		)
		(instances
			(project "com-express-7-baseboard"
				(path ""
					(reference "#PWR0235")
					(unit 1)
				)
			)
		)
	)
	(symbol
		(lib_id "antmicroTestPoints:TP_0.75mm_SMD")
		(at 76.2 137.16 0)
		(unit 1)
		(exclude_from_sim no)
		(in_bom no)
		(on_board yes)
		(dnp no)
		(fields_autoplaced yes)
		(property "Reference" "TP32"
			(at 81.28 137.16 0)
			(effects
				(font
					(size 1.27 1.27)
					(thickness 0.15)
				)
				(justify left)
			)
		)
		(property "Value" "TP_0.75mm_SMD"
			(at 86.995 140.97 0)
			(effects
				(font
					(size 1.27 1.27)
					(thickness 0.15)
				)
				(justify left bottom)
				(hide yes)
			)
		)
		(property "Footprint" "antmicro-footprints:TP_SMD_0.75mm"
			(at 86.995 143.51 0)
			(effects
				(font
					(size 1.27 1.27)
					(thickness 0.15)
				)
				(justify left bottom)
				(hide yes)
			)
		)
		(property "Datasheet" ""
			(at 93.98 149.86 0)
			(effects
				(font
					(size 1.27 1.27)
					(thickness 0.15)
				)
				(justify left bottom)
				(hide yes)
			)
		)
		(property "Description" ""
			(at 76.2 137.16 0)
			(effects
				(font
					(size 1.27 1.27)
				)
				(hide yes)
			)
		)
		(property "MPN" ""
			(at 86.995 148.59 0)
			(effects
				(font
					(size 1.27 1.27)
					(thickness 0.15)
				)
				(justify left bottom)
				(hide yes)
			)
		)
		(property "Manufacturer" ""
			(at 86.995 143.51 0)
			(effects
				(font
					(size 1.27 1.27)
					(thickness 0.15)
				)
				(justify left bottom)
				(hide yes)
			)
		)
		(property "Author" "Antmicro"
			(at 86.995 146.05 0)
			(effects
				(font
					(size 1.27 1.27)
					(thickness 0.15)
				)
				(justify left bottom)
				(hide yes)
			)
		)
		(property "License" "Apache-2.0"
			(at 86.995 148.59 0)
			(effects
				(font
					(size 1.27 1.27)
					(thickness 0.15)
				)
				(justify left bottom)
				(hide yes)
			)
		)
		(property "Public" "False"
			(at 86.36 151.13 0)
			(effects
				(font
					(size 1.27 1.27)
				)
				(justify left bottom)
				(hide yes)
			)
		)
		(pin "1"
		)
		(instances
			(project "com-express-7-baseboard"
				(path ""
					(reference "TP32")
					(unit 1)
				)
			)
		)
	)
	(symbol
		(lib_id "antmicroCapacitors0402:C_100n_0402")
		(at 259.08 215.9 270)
		(mirror x)
		(unit 1)
		(exclude_from_sim no)
		(in_bom yes)
		(on_board yes)
		(dnp no)
		(fields_autoplaced yes)
		(property "Reference" "C100"
			(at 261.62 212.0836 90)
			(effects
				(font
					(size 1.27 1.27)
					(thickness 0.15)
				)
				(justify left)
			)
		)
		(property "Value" "C_100n_0402"
			(at 248.92 195.58 0)
			(effects
				(font
					(size 1.27 1.27)
					(thickness 0.15)
				)
				(justify left bottom)
				(hide yes)
			)
		)
		(property "Footprint" "antmicro-footprints:C_0402_1005Metric"
			(at 246.38 195.58 0)
			(effects
				(font
					(size 1.27 1.27)
					(thickness 0.15)
				)
				(justify left bottom)
				(hide yes)
			)
		)
		(property "Datasheet" "https://www.murata.com/products/productdetail?partno=GRM155R61H104KE14%23"
			(at 243.84 195.58 0)
			(effects
				(font
					(size 1.27 1.27)
					(thickness 0.15)
				)
				(justify left bottom)
				(hide yes)
			)
		)
		(property "Description" ""
			(at 259.08 215.9 0)
			(effects
				(font
					(size 1.27 1.27)
				)
				(hide yes)
			)
		)
		(property "MPN" "GRM155R61H104KE14D"
			(at 241.3 195.58 0)
			(effects
				(font
					(size 1.27 1.27)
					(thickness 0.15)
				)
				(justify left bottom)
				(hide yes)
			)
		)
		(property "Manufacturer" "Murata"
			(at 238.76 195.58 0)
			(effects
				(font
					(size 1.27 1.27)
					(thickness 0.15)
				)
				(justify left bottom)
				(hide yes)
			)
		)
		(property "License" "Apache-2.0"
			(at 236.22 195.58 0)
			(effects
				(font
					(size 1.27 1.27)
					(thickness 0.15)
				)
				(justify left bottom)
				(hide yes)
			)
		)
		(property "Author" "Antmicro"
			(at 233.68 195.58 0)
			(effects
				(font
					(size 1.27 1.27)
					(thickness 0.15)
				)
				(justify left bottom)
				(hide yes)
			)
		)
		(property "Val" "100n"
			(at 261.62 214.6236 90)
			(effects
				(font
					(size 1.27 1.27)
					(thickness 0.15)
				)
				(justify left)
			)
		)
		(property "Voltage" "50V"
			(at 231.14 195.58 0)
			(effects
				(font
					(size 1.27 1.27)
				)
				(justify left bottom)
				(hide yes)
			)
		)
		(property "Dielectric" "X5R"
			(at 228.6 195.58 0)
			(effects
				(font
					(size 1.27 1.27)
				)
				(justify left bottom)
				(hide yes)
			)
		)
		(property "Public" "False"
			(at 226.06 195.58 0)
			(effects
				(font
					(size 1.27 1.27)
				)
				(justify left bottom)
				(hide yes)
			)
		)
		(pin "2"
		)
		(pin "1"
		)
		(instances
			(project "com-express-7-baseboard"
				(path ""
					(reference "C100")
					(unit 1)
				)
			)
		)
	)
	(symbol
		(lib_id "antmicroResistors0402:R_1k_0402")
		(at 330.2 60.96 180)
		(unit 1)
		(exclude_from_sim no)
		(in_bom yes)
		(on_board yes)
		(dnp no)
		(property "Reference" "R323"
			(at 322.58 59.69 0)
			(effects
				(font
					(size 1.27 1.27)
					(thickness 0.15)
				)
			)
		)
		(property "Value" "R_1k_0402"
			(at 309.88 48.26 0)
			(effects
				(font
					(size 1.27 1.27)
					(thickness 0.15)
				)
				(justify left bottom)
				(hide yes)
			)
		)
		(property "Footprint" "antmicro-footprints:R_0402_1005Metric"
			(at 309.88 45.72 0)
			(effects
				(font
					(size 1.27 1.27)
					(thickness 0.15)
				)
				(justify left bottom)
				(hide yes)
			)
		)
		(property "Datasheet" "https://www.bourns.com/docs/product-datasheets/cr.pdf"
			(at 309.88 43.18 0)
			(effects
				(font
					(size 1.27 1.27)
					(thickness 0.15)
				)
				(justify left bottom)
				(hide yes)
			)
		)
		(property "Description" ""
			(at 330.2 60.96 0)
			(effects
				(font
					(size 1.27 1.27)
				)
				(hide yes)
			)
		)
		(property "MPN" "CR0402-FX-1001GLF"
			(at 309.88 40.64 0)
			(effects
				(font
					(size 1.27 1.27)
					(thickness 0.15)
				)
				(justify left bottom)
				(hide yes)
			)
		)
		(property "Manufacturer" "Bourns"
			(at 309.88 38.1 0)
			(effects
				(font
					(size 1.27 1.27)
					(thickness 0.15)
				)
				(justify left bottom)
				(hide yes)
			)
		)
		(property "License" "Apache-2.0"
			(at 309.88 35.56 0)
			(effects
				(font
					(size 1.27 1.27)
					(thickness 0.15)
				)
				(justify left bottom)
				(hide yes)
			)
		)
		(property "Author" "Antmicro"
			(at 309.88 33.02 0)
			(effects
				(font
					(size 1.27 1.27)
					(thickness 0.15)
				)
				(justify left bottom)
				(hide yes)
			)
		)
		(property "Val" "1k"
			(at 331.47 59.69 0)
			(effects
				(font
					(size 1.27 1.27)
					(thickness 0.15)
				)
			)
		)
		(property "Tolerance" "1%"
			(at 309.88 50.8 0)
			(effects
				(font
					(size 1.27 1.27)
				)
				(justify left bottom)
				(hide yes)
			)
		)
		(property "Public" "False"
			(at 309.88 30.48 0)
			(effects
				(font
					(size 1.27 1.27)
				)
				(justify left bottom)
				(hide yes)
			)
		)
		(pin "2"
		)
		(pin "1"
		)
		(instances
			(project "com-express-7-baseboard"
				(path ""
					(reference "R323")
					(unit 1)
				)
			)
		)
	)
	(symbol
		(lib_id "antmicropower:GND")
		(at 307.34 78.74 0)
		(unit 1)
		(exclude_from_sim no)
		(in_bom yes)
		(on_board yes)
		(dnp no)
		(property "Reference" "#PWR0449"
			(at 316.23 81.28 0)
			(effects
				(font
					(size 1.27 1.27)
					(thickness 0.15)
				)
				(justify left bottom)
				(hide yes)
			)
		)
		(property "Value" "GND"
			(at 307.34 82.55 0)
			(effects
				(font
					(size 1.27 1.27)
					(thickness 0.15)
				)
			)
		)
		(property "Footprint" ""
			(at 316.23 86.36 0)
			(effects
				(font
					(size 1.27 1.27)
					(thickness 0.15)
				)
				(justify left bottom)
				(hide yes)
			)
		)
		(property "Datasheet" ""
			(at 316.23 91.44 0)
			(effects
				(font
					(size 1.27 1.27)
					(thickness 0.15)
				)
				(justify left bottom)
				(hide yes)
			)
		)
		(property "Description" ""
			(at 307.34 78.74 0)
			(effects
				(font
					(size 1.27 1.27)
				)
				(hide yes)
			)
		)
		(property "Author" "Antmicro"
			(at 316.23 86.36 0)
			(effects
				(font
					(size 1.27 1.27)
					(thickness 0.15)
				)
				(justify left bottom)
				(hide yes)
			)
		)
		(property "License" "Apache-2.0"
			(at 316.23 88.9 0)
			(effects
				(font
					(size 1.27 1.27)
					(thickness 0.15)
				)
				(justify left bottom)
				(hide yes)
			)
		)
		(pin "1"
		)
		(instances
			(project "com-express-7-baseboard"
				(path ""
					(reference "#PWR0449")
					(unit 1)
				)
			)
		)
	)
	(symbol
		(lib_id "antmicroCapacitors0402:C_100n_0402")
		(at 285.75 134.62 90)
		(unit 1)
		(exclude_from_sim no)
		(in_bom yes)
		(on_board yes)
		(dnp no)
		(fields_autoplaced yes)
		(property "Reference" "C99"
			(at 288.29 130.8036 90)
			(effects
				(font
					(size 1.27 1.27)
					(thickness 0.15)
				)
				(justify right)
			)
		)
		(property "Value" "C_100n_0402"
			(at 295.91 114.3 0)
			(effects
				(font
					(size 1.27 1.27)
					(thickness 0.15)
				)
				(justify left bottom)
				(hide yes)
			)
		)
		(property "Footprint" "antmicro-footprints:C_0402_1005Metric"
			(at 298.45 114.3 0)
			(effects
				(font
					(size 1.27 1.27)
					(thickness 0.15)
				)
				(justify left bottom)
				(hide yes)
			)
		)
		(property "Datasheet" "https://www.murata.com/products/productdetail?partno=GRM155R61H104KE14%23"
			(at 300.99 114.3 0)
			(effects
				(font
					(size 1.27 1.27)
					(thickness 0.15)
				)
				(justify left bottom)
				(hide yes)
			)
		)
		(property "Description" ""
			(at 285.75 134.62 0)
			(effects
				(font
					(size 1.27 1.27)
				)
				(hide yes)
			)
		)
		(property "MPN" "GRM155R61H104KE14D"
			(at 303.53 114.3 0)
			(effects
				(font
					(size 1.27 1.27)
					(thickness 0.15)
				)
				(justify left bottom)
				(hide yes)
			)
		)
		(property "Manufacturer" "Murata"
			(at 306.07 114.3 0)
			(effects
				(font
					(size 1.27 1.27)
					(thickness 0.15)
				)
				(justify left bottom)
				(hide yes)
			)
		)
		(property "License" "Apache-2.0"
			(at 308.61 114.3 0)
			(effects
				(font
					(size 1.27 1.27)
					(thickness 0.15)
				)
				(justify left bottom)
				(hide yes)
			)
		)
		(property "Author" "Antmicro"
			(at 311.15 114.3 0)
			(effects
				(font
					(size 1.27 1.27)
					(thickness 0.15)
				)
				(justify left bottom)
				(hide yes)
			)
		)
		(property "Val" "100n"
			(at 288.29 133.3436 90)
			(effects
				(font
					(size 1.27 1.27)
					(thickness 0.15)
				)
				(justify right)
			)
		)
		(property "Voltage" "50V"
			(at 313.69 114.3 0)
			(effects
				(font
					(size 1.27 1.27)
				)
				(justify left bottom)
				(hide yes)
			)
		)
		(property "Dielectric" "X5R"
			(at 316.23 114.3 0)
			(effects
				(font
					(size 1.27 1.27)
				)
				(justify left bottom)
				(hide yes)
			)
		)
		(property "Public" "False"
			(at 318.77 114.3 0)
			(effects
				(font
					(size 1.27 1.27)
				)
				(justify left bottom)
				(hide yes)
			)
		)
		(pin "2"
		)
		(pin "1"
		)
		(instances
			(project "com-express-7-baseboard"
				(path ""
					(reference "C99")
					(unit 1)
				)
			)
		)
	)
	(symbol
		(lib_id "antmicroResistors0402:R_100k_0402")
		(at 284.48 158.75 90)
		(unit 1)
		(exclude_from_sim no)
		(in_bom yes)
		(on_board yes)
		(dnp no)
		(property "Reference" "R172"
			(at 285.75 154.94 90)
			(effects
				(font
					(size 1.27 1.27)
					(thickness 0.15)
				)
				(justify right)
			)
		)
		(property "Value" "R_100k_0402"
			(at 297.18 138.43 0)
			(effects
				(font
					(size 1.27 1.27)
					(thickness 0.15)
				)
				(justify left bottom)
				(hide yes)
			)
		)
		(property "Footprint" "antmicro-footprints:R_0402_1005Metric"
			(at 299.72 138.43 0)
			(effects
				(font
					(size 1.27 1.27)
					(thickness 0.15)
				)
				(justify left bottom)
				(hide yes)
			)
		)
		(property "Datasheet" "https://www.bourns.com/docs/product-datasheets/cr.pdf"
			(at 302.26 138.43 0)
			(effects
				(font
					(size 1.27 1.27)
					(thickness 0.15)
				)
				(justify left bottom)
				(hide yes)
			)
		)
		(property "Description" ""
			(at 284.48 158.75 0)
			(effects
				(font
					(size 1.27 1.27)
				)
				(hide yes)
			)
		)
		(property "MPN" "CR0402-FX-1003GLF"
			(at 304.8 138.43 0)
			(effects
				(font
					(size 1.27 1.27)
					(thickness 0.15)
				)
				(justify left bottom)
				(hide yes)
			)
		)
		(property "Manufacturer" "Bourns"
			(at 307.34 138.43 0)
			(effects
				(font
					(size 1.27 1.27)
					(thickness 0.15)
				)
				(justify left bottom)
				(hide yes)
			)
		)
		(property "License" "Apache-2.0"
			(at 309.88 138.43 0)
			(effects
				(font
					(size 1.27 1.27)
					(thickness 0.15)
				)
				(justify left bottom)
				(hide yes)
			)
		)
		(property "Author" "Antmicro"
			(at 312.42 138.43 0)
			(effects
				(font
					(size 1.27 1.27)
					(thickness 0.15)
				)
				(justify left bottom)
				(hide yes)
			)
		)
		(property "Val" "100k"
			(at 285.75 157.48 90)
			(effects
				(font
					(size 1.27 1.27)
					(thickness 0.15)
				)
				(justify right)
			)
		)
		(property "Tolerance" "1%"
			(at 294.64 138.43 0)
			(effects
				(font
					(size 1.27 1.27)
				)
				(justify left bottom)
				(hide yes)
			)
		)
		(property "Public" "False"
			(at 314.96 138.43 0)
			(effects
				(font
					(size 1.27 1.27)
				)
				(justify left bottom)
				(hide yes)
			)
		)
		(pin "1"
		)
		(pin "2"
		)
		(instances
			(project "com-express-7-baseboard"
				(path ""
					(reference "R172")
					(unit 1)
				)
			)
		)
	)
	(symbol
		(lib_id "antmicroLogicGatesandInverters:74AUP2G132")
		(at 123.19 137.16 0)
		(unit 1)
		(exclude_from_sim no)
		(in_bom yes)
		(on_board yes)
		(dnp no)
		(fields_autoplaced yes)
		(property "Reference" "U30"
			(at 132.08 130.81 0)
			(effects
				(font
					(size 1.27 1.27)
					(thickness 0.15)
				)
			)
		)
		(property "Value" "74AUP2G132"
			(at 168.91 147.32 0)
			(effects
				(font
					(size 1.27 1.27)
					(thickness 0.15)
				)
				(justify left bottom)
				(hide yes)
			)
		)
		(property "Footprint" "antmicro-footprints:VSSOP-8_2.3x2mm_P0.5mm"
			(at 168.91 149.86 0)
			(effects
				(font
					(size 1.27 1.27)
					(thickness 0.15)
				)
				(justify left bottom)
				(hide yes)
			)
		)
		(property "Datasheet" "https://assets.nexperia.com/documents/data-sheet/74AUP2G132.pdf"
			(at 168.91 152.4 0)
			(effects
				(font
					(size 1.27 1.27)
					(thickness 0.15)
				)
				(justify left bottom)
				(hide yes)
			)
		)
		(property "Description" ""
			(at 123.19 137.16 0)
			(effects
				(font
					(size 1.27 1.27)
				)
				(hide yes)
			)
		)
		(property "Manufacturer" "Nexperia"
			(at 168.91 154.94 0)
			(effects
				(font
					(size 1.27 1.27)
					(thickness 0.15)
				)
				(justify left bottom)
				(hide yes)
			)
		)
		(property "MPN" "74AUP2G132"
			(at 132.08 133.35 0)
			(effects
				(font
					(size 1.27 1.27)
					(thickness 0.15)
				)
			)
		)
		(property "Author" "Antmicro"
			(at 168.91 157.48 0)
			(effects
				(font
					(size 1.27 1.27)
					(thickness 0.15)
				)
				(justify left bottom)
				(hide yes)
			)
		)
		(property "License" "Apache-2.0"
			(at 168.91 160.02 0)
			(effects
				(font
					(size 1.27 1.27)
					(thickness 0.15)
				)
				(justify left bottom)
				(hide yes)
			)
		)
		(pin "4"
		)
		(pin "2"
		)
		(pin "3"
		)
		(pin "1"
		)
		(pin "5"
		)
		(pin "8"
		)
		(pin "6"
		)
		(pin "7"
		)
		(instances
			(project "com-express-7-baseboard"
				(path ""
					(reference "U30")
					(unit 1)
				)
			)
		)
	)
	(symbol
		(lib_id "antmicroTestPoints:TP_0.75mm_SMD")
		(at 76.2 180.34 0)
		(unit 1)
		(exclude_from_sim no)
		(in_bom no)
		(on_board yes)
		(dnp no)
		(fields_autoplaced yes)
		(property "Reference" "TP37"
			(at 81.28 180.34 0)
			(effects
				(font
					(size 1.27 1.27)
					(thickness 0.15)
				)
				(justify left)
			)
		)
		(property "Value" "TP_0.75mm_SMD"
			(at 86.995 184.15 0)
			(effects
				(font
					(size 1.27 1.27)
					(thickness 0.15)
				)
				(justify left bottom)
				(hide yes)
			)
		)
		(property "Footprint" "antmicro-footprints:TP_SMD_0.75mm"
			(at 86.995 186.69 0)
			(effects
				(font
					(size 1.27 1.27)
					(thickness 0.15)
				)
				(justify left bottom)
				(hide yes)
			)
		)
		(property "Datasheet" ""
			(at 93.98 193.04 0)
			(effects
				(font
					(size 1.27 1.27)
					(thickness 0.15)
				)
				(justify left bottom)
				(hide yes)
			)
		)
		(property "Description" ""
			(at 76.2 180.34 0)
			(effects
				(font
					(size 1.27 1.27)
				)
				(hide yes)
			)
		)
		(property "MPN" ""
			(at 86.995 191.77 0)
			(effects
				(font
					(size 1.27 1.27)
					(thickness 0.15)
				)
				(justify left bottom)
				(hide yes)
			)
		)
		(property "Manufacturer" ""
			(at 86.995 186.69 0)
			(effects
				(font
					(size 1.27 1.27)
					(thickness 0.15)
				)
				(justify left bottom)
				(hide yes)
			)
		)
		(property "Author" "Antmicro"
			(at 86.995 189.23 0)
			(effects
				(font
					(size 1.27 1.27)
					(thickness 0.15)
				)
				(justify left bottom)
				(hide yes)
			)
		)
		(property "License" "Apache-2.0"
			(at 86.995 191.77 0)
			(effects
				(font
					(size 1.27 1.27)
					(thickness 0.15)
				)
				(justify left bottom)
				(hide yes)
			)
		)
		(property "Public" "False"
			(at 86.36 194.31 0)
			(effects
				(font
					(size 1.27 1.27)
				)
				(justify left bottom)
				(hide yes)
			)
		)
		(pin "1"
		)
		(instances
			(project "com-express-7-baseboard"
				(path ""
					(reference "TP37")
					(unit 1)
				)
			)
		)
	)
	(symbol
		(lib_id "antmicropower:GND")
		(at 116.84 83.82 0)
		(unit 1)
		(exclude_from_sim no)
		(in_bom yes)
		(on_board yes)
		(dnp no)
		(property "Reference" "#PWR0238"
			(at 125.73 86.36 0)
			(effects
				(font
					(size 1.27 1.27)
					(thickness 0.15)
				)
				(justify left bottom)
				(hide yes)
			)
		)
		(property "Value" "GND"
			(at 116.84 87.63 0)
			(effects
				(font
					(size 1.27 1.27)
					(thickness 0.15)
				)
			)
		)
		(property "Footprint" ""
			(at 125.73 91.44 0)
			(effects
				(font
					(size 1.27 1.27)
					(thickness 0.15)
				)
				(justify left bottom)
				(hide yes)
			)
		)
		(property "Datasheet" ""
			(at 125.73 96.52 0)
			(effects
				(font
					(size 1.27 1.27)
					(thickness 0.15)
				)
				(justify left bottom)
				(hide yes)
			)
		)
		(property "Description" ""
			(at 116.84 83.82 0)
			(effects
				(font
					(size 1.27 1.27)
				)
				(hide yes)
			)
		)
		(property "Author" "Antmicro"
			(at 125.73 91.44 0)
			(effects
				(font
					(size 1.27 1.27)
					(thickness 0.15)
				)
				(justify left bottom)
				(hide yes)
			)
		)
		(property "License" "Apache-2.0"
			(at 125.73 93.98 0)
			(effects
				(font
					(size 1.27 1.27)
					(thickness 0.15)
				)
				(justify left bottom)
				(hide yes)
			)
		)
		(pin "1"
		)
		(instances
			(project "com-express-7-baseboard"
				(path ""
					(reference "#PWR0238")
					(unit 1)
				)
			)
		)
	)
	(symbol
		(lib_id "antmicroResistors0402:R_1k_0402")
		(at 350.52 231.14 0)
		(unit 1)
		(exclude_from_sim no)
		(in_bom yes)
		(on_board yes)
		(dnp no)
		(property "Reference" "R180"
			(at 347.98 229.87 0)
			(effects
				(font
					(size 1.27 1.27)
					(thickness 0.15)
				)
			)
		)
		(property "Value" "R_1k_0402"
			(at 370.84 243.84 0)
			(effects
				(font
					(size 1.27 1.27)
					(thickness 0.15)
				)
				(justify left bottom)
				(hide yes)
			)
		)
		(property "Footprint" "antmicro-footprints:R_0402_1005Metric"
			(at 370.84 246.38 0)
			(effects
				(font
					(size 1.27 1.27)
					(thickness 0.15)
				)
				(justify left bottom)
				(hide yes)
			)
		)
		(property "Datasheet" "https://www.bourns.com/docs/product-datasheets/cr.pdf"
			(at 370.84 248.92 0)
			(effects
				(font
					(size 1.27 1.27)
					(thickness 0.15)
				)
				(justify left bottom)
				(hide yes)
			)
		)
		(property "Description" ""
			(at 350.52 231.14 0)
			(effects
				(font
					(size 1.27 1.27)
				)
				(hide yes)
			)
		)
		(property "MPN" "CR0402-FX-1001GLF"
			(at 370.84 251.46 0)
			(effects
				(font
					(size 1.27 1.27)
					(thickness 0.15)
				)
				(justify left bottom)
				(hide yes)
			)
		)
		(property "Manufacturer" "Bourns"
			(at 370.84 254 0)
			(effects
				(font
					(size 1.27 1.27)
					(thickness 0.15)
				)
				(justify left bottom)
				(hide yes)
			)
		)
		(property "License" "Apache-2.0"
			(at 370.84 256.54 0)
			(effects
				(font
					(size 1.27 1.27)
					(thickness 0.15)
				)
				(justify left bottom)
				(hide yes)
			)
		)
		(property "Author" "Antmicro"
			(at 370.84 259.08 0)
			(effects
				(font
					(size 1.27 1.27)
					(thickness 0.15)
				)
				(justify left bottom)
				(hide yes)
			)
		)
		(property "Val" "1k"
			(at 356.87 229.87 0)
			(effects
				(font
					(size 1.27 1.27)
					(thickness 0.15)
				)
			)
		)
		(property "Tolerance" "1%"
			(at 370.84 241.3 0)
			(effects
				(font
					(size 1.27 1.27)
				)
				(justify left bottom)
				(hide yes)
			)
		)
		(property "Public" "False"
			(at 370.84 261.62 0)
			(effects
				(font
					(size 1.27 1.27)
				)
				(justify left bottom)
				(hide yes)
			)
		)
		(pin "2"
		)
		(pin "1"
		)
		(instances
			(project "com-express-7-baseboard"
				(path ""
					(reference "R180")
					(unit 1)
				)
			)
		)
	)
	(symbol
		(lib_id "antmicropower:GND")
		(at 104.14 46.99 0)
		(unit 1)
		(exclude_from_sim no)
		(in_bom yes)
		(on_board yes)
		(dnp no)
		(property "Reference" "#PWR0232"
			(at 113.03 49.53 0)
			(effects
				(font
					(size 1.27 1.27)
					(thickness 0.15)
				)
				(justify left bottom)
				(hide yes)
			)
		)
		(property "Value" "GND"
			(at 104.14 50.8 0)
			(effects
				(font
					(size 1.27 1.27)
					(thickness 0.15)
				)
			)
		)
		(property "Footprint" ""
			(at 113.03 54.61 0)
			(effects
				(font
					(size 1.27 1.27)
					(thickness 0.15)
				)
				(justify left bottom)
				(hide yes)
			)
		)
		(property "Datasheet" ""
			(at 113.03 59.69 0)
			(effects
				(font
					(size 1.27 1.27)
					(thickness 0.15)
				)
				(justify left bottom)
				(hide yes)
			)
		)
		(property "Description" ""
			(at 104.14 46.99 0)
			(effects
				(font
					(size 1.27 1.27)
				)
				(hide yes)
			)
		)
		(property "Author" "Antmicro"
			(at 113.03 54.61 0)
			(effects
				(font
					(size 1.27 1.27)
					(thickness 0.15)
				)
				(justify left bottom)
				(hide yes)
			)
		)
		(property "License" "Apache-2.0"
			(at 113.03 57.15 0)
			(effects
				(font
					(size 1.27 1.27)
					(thickness 0.15)
				)
				(justify left bottom)
				(hide yes)
			)
		)
		(pin "1"
		)
		(instances
			(project "com-express-7-baseboard"
				(path ""
					(reference "#PWR0232")
					(unit 1)
				)
			)
		)
	)
	(symbol
		(lib_id "antmicropower:+3V3")
		(at 102.87 161.29 0)
		(unit 1)
		(exclude_from_sim no)
		(in_bom yes)
		(on_board yes)
		(dnp no)
		(property "Reference" "#PWR0230"
			(at 118.11 161.29 0)
			(effects
				(font
					(size 1.27 1.27)
					(thickness 0.15)
				)
				(justify left bottom)
				(hide yes)
			)
		)
		(property "Value" "+3V3"
			(at 102.87 157.48 0)
			(effects
				(font
					(size 1.27 1.27)
					(thickness 0.15)
				)
			)
		)
		(property "Footprint" ""
			(at 118.11 168.91 0)
			(effects
				(font
					(size 1.27 1.27)
					(thickness 0.15)
				)
				(justify left bottom)
				(hide yes)
			)
		)
		(property "Datasheet" ""
			(at 118.11 171.45 0)
			(effects
				(font
					(size 1.27 1.27)
					(thickness 0.15)
				)
				(justify left bottom)
				(hide yes)
			)
		)
		(property "Description" ""
			(at 102.87 161.29 0)
			(effects
				(font
					(size 1.27 1.27)
				)
				(hide yes)
			)
		)
		(property "Author" "Antmicro"
			(at 118.11 163.83 0)
			(effects
				(font
					(size 1.27 1.27)
					(thickness 0.15)
				)
				(justify left bottom)
				(hide yes)
			)
		)
		(property "License" "Apache-2.0"
			(at 118.11 166.37 0)
			(effects
				(font
					(size 1.27 1.27)
					(thickness 0.15)
				)
				(justify left bottom)
				(hide yes)
			)
		)
		(pin "1"
		)
		(instances
			(project "com-express-7-baseboard"
				(path ""
					(reference "#PWR0230")
					(unit 1)
				)
			)
		)
	)
	(symbol
		(lib_id "antmicroPMICPowerSequencers:LTC2950CTS8-1")
		(at 279.4 60.96 0)
		(unit 1)
		(exclude_from_sim no)
		(in_bom yes)
		(on_board yes)
		(dnp no)
		(fields_autoplaced yes)
		(property "Reference" "U34"
			(at 289.56 53.34 0)
			(effects
				(font
					(size 1.27 1.27)
					(thickness 0.15)
				)
			)
		)
		(property "Value" "LTC2950CTS8-1"
			(at 314.96 68.58 0)
			(effects
				(font
					(size 1.27 1.27)
					(thickness 0.15)
				)
				(justify left bottom)
				(hide yes)
			)
		)
		(property "Footprint" "antmicro-footprints:SOT-23-8"
			(at 314.96 71.12 0)
			(effects
				(font
					(size 1.27 1.27)
					(thickness 0.15)
				)
				(justify left bottom)
				(hide yes)
			)
		)
		(property "Datasheet" "https://www.analog.com/media/en/technical-documentation/data-sheets/295012fd.pdf"
			(at 314.96 73.66 0)
			(effects
				(font
					(size 1.27 1.27)
					(thickness 0.15)
				)
				(justify left bottom)
				(hide yes)
			)
		)
		(property "Description" ""
			(at 279.4 60.96 0)
			(effects
				(font
					(size 1.27 1.27)
				)
				(hide yes)
			)
		)
		(property "MPN" "LTC2950CTS8-1"
			(at 289.56 55.88 0)
			(effects
				(font
					(size 1.27 1.27)
					(thickness 0.15)
				)
			)
		)
		(property "Manufacturer" "Analog Devices"
			(at 314.96 76.2 0)
			(effects
				(font
					(size 1.27 1.27)
					(thickness 0.15)
				)
				(justify left bottom)
				(hide yes)
			)
		)
		(property "Author" "Antmicro"
			(at 314.96 78.74 0)
			(effects
				(font
					(size 1.27 1.27)
					(thickness 0.15)
				)
				(justify left bottom)
				(hide yes)
			)
		)
		(property "License" "Apache-2.0"
			(at 314.96 81.28 0)
			(effects
				(font
					(size 1.27 1.27)
					(thickness 0.15)
				)
				(justify left bottom)
				(hide yes)
			)
		)
		(pin "4"
		)
		(pin "8"
		)
		(pin "5"
		)
		(pin "1"
		)
		(pin "7"
		)
		(pin "6"
		)
		(pin "3"
		)
		(pin "2"
		)
		(instances
			(project "com-express-7-baseboard"
				(path ""
					(reference "U34")
					(unit 1)
				)
			)
		)
	)
	(symbol
		(lib_id "antmicroB2BConnectors:Plug_Bus_CE7_EPT_401-51501-51")
		(at 76.2 38.1 0)
		(unit 13)
		(exclude_from_sim no)
		(in_bom yes)
		(on_board yes)
		(dnp no)
		(fields_autoplaced yes)
		(property "Reference" "J12"
			(at 57.15 30.48 0)
			(effects
				(font
					(size 1.27 1.27)
					(thickness 0.15)
				)
			)
		)
		(property "Value" "Plug_Bus_CE7_EPT_401-51501-51"
			(at 129.54 50.8 0)
			(effects
				(font
					(size 1.27 1.27)
					(thickness 0.15)
				)
				(justify left bottom)
				(hide yes)
			)
		)
		(property "Footprint" "antmicro-footprints:EPT_401-51501-51"
			(at 129.54 53.34 0)
			(effects
				(font
					(size 1.27 1.27)
					(thickness 0.15)
				)
				(justify left bottom)
				(hide yes)
			)
		)
		(property "Datasheet" "https://www.farnell.com/datasheets/1905093.pdf"
			(at 129.54 55.88 0)
			(effects
				(font
					(size 1.27 1.27)
					(thickness 0.15)
				)
				(justify left bottom)
				(hide yes)
			)
		)
		(property "Description" ""
			(at 76.2 38.1 0)
			(effects
				(font
					(size 1.27 1.27)
				)
				(hide yes)
			)
		)
		(property "Author" "Antmicro"
			(at 129.54 58.42 0)
			(effects
				(font
					(size 1.27 1.27)
					(thickness 0.15)
				)
				(justify left bottom)
				(hide yes)
			)
		)
		(property "License" "Apache-2.0"
			(at 129.54 60.96 0)
			(effects
				(font
					(size 1.27 1.27)
					(thickness 0.15)
				)
				(justify left bottom)
				(hide yes)
			)
		)
		(property "Manufacturer" "ept"
			(at 129.54 43.18 0)
			(effects
				(font
					(size 1.27 1.27)
					(thickness 0.15)
				)
				(justify left bottom)
				(hide yes)
			)
		)
		(property "MPN" "401-51501-51"
			(at 57.15 33.02 0)
			(effects
				(font
					(size 1.27 1.27)
					(thickness 0.15)
				)
			)
		)
		(pin "C91"
		)
		(pin "C92"
		)
		(pin "A15"
		)
		(pin "A91"
		)
		(pin "C34"
		)
		(pin "C35"
		)
		(pin "D22"
		)
		(pin "D23"
		)
		(pin "D55"
		)
		(pin "D56"
		)
		(pin "C55"
		)
		(pin "C56"
		)
		(pin "C71"
		)
		(pin "C72"
		)
		(pin "C32"
		)
		(pin "C33"
		)
		(pin "B6"
		)
		(pin "B58"
		)
		(pin "B59"
		)
		(pin "D5"
		)
		(pin "D51"
		)
		(pin "A29"
		)
		(pin "D46"
		)
		(pin "D47"
		)
		(pin "C105"
		)
		(pin "C106"
		)
		(pin "A16"
		)
		(pin "B22"
		)
		(pin "B51"
		)
		(pin "B30"
		)
		(pin "A44"
		)
		(pin "C51"
		)
		(pin "C60"
		)
		(pin "A81"
		)
		(pin "A82"
		)
		(pin "D90"
		)
		(pin "D93"
		)
		(pin "B68"
		)
		(pin "B69"
		)
		(pin "C103"
		)
		(pin "C104"
		)
		(pin "C58"
		)
		(pin "C59"
		)
		(pin "D84"
		)
		(pin "D87"
		)
		(pin "A30"
		)
		(pin "B29"
		)
		(pin "A41"
		)
		(pin "C40"
		)
		(pin "C42"
		)
		(pin "D80"
		)
		(pin "D83"
		)
		(pin "B103"
		)
		(pin "A102"
		)
		(pin "C101"
		)
		(pin "C102"
		)
		(pin "D11"
		)
		(pin "D110"
		)
		(pin "B37"
		)
		(pin "B45"
		)
		(pin "C61"
		)
		(pin "C62"
		)
		(pin "A42"
		)
		(pin "B36"
		)
		(pin "B57"
		)
		(pin "D12"
		)
		(pin "D44"
		)
		(pin "D48"
		)
		(pin "B32"
		)
		(pin "B107"
		)
		(pin "B108"
		)
		(pin "B110"
		)
		(pin "B101"
		)
		(pin "C63"
		)
		(pin "C64"
		)
		(pin "B50"
		)
		(pin "A87"
		)
		(pin "A86"
		)
		(pin "B27"
		)
		(pin "D17"
		)
		(pin "D24"
		)
		(pin "D26"
		)
		(pin "D27"
		)
		(pin "A47"
		)
		(pin "C81"
		)
		(pin "C82"
		)
		(pin "C68"
		)
		(pin "C69"
		)
		(pin "A74"
		)
		(pin "A48"
		)
		(pin "A57"
		)
		(pin "A43"
		)
		(pin "A31"
		)
		(pin "D29"
		)
		(pin "D30"
		)
		(pin "C36"
		)
		(pin "C37"
		)
		(pin "C3"
		)
		(pin "A35"
		)
		(pin "A34"
		)
		(pin "B7"
		)
		(pin "B46"
		)
		(pin "B1"
		)
		(pin "B63"
		)
		(pin "A51"
		)
		(pin "A99"
		)
		(pin "B17"
		)
		(pin "C13"
		)
		(pin "C4"
		)
		(pin "B102"
		)
		(pin "C38"
		)
		(pin "C39"
		)
		(pin "B3"
		)
		(pin "A90"
		)
		(pin "A72"
		)
		(pin "B84"
		)
		(pin "D19"
		)
		(pin "D20"
		)
		(pin "D43"
		)
		(pin "D45"
		)
		(pin "A77"
		)
		(pin "A78"
		)
		(pin "B38"
		)
		(pin "B86"
		)
		(pin "D77"
		)
		(pin "D8"
		)
		(pin "A32"
		)
		(pin "B85"
		)
		(pin "D73"
		)
		(pin "D76"
		)
		(pin "D63"
		)
		(pin "D64"
		)
		(pin "D67"
		)
		(pin "D70"
		)
		(pin "B83"
		)
		(pin "D81"
		)
		(pin "D82"
		)
		(pin "B41"
		)
		(pin "D49"
		)
		(pin "D50"
		)
		(pin "A75"
		)
		(pin "D2"
		)
		(pin "D21"
		)
		(pin "C78"
		)
		(pin "C79"
		)
		(pin "B19"
		)
		(pin "B39"
		)
		(pin "A12"
		)
		(pin "B66"
		)
		(pin "D4"
		)
		(pin "D85"
		)
		(pin "D86"
		)
		(pin "A105"
		)
		(pin "B90"
		)
		(pin "A22"
		)
		(pin "A109"
		)
		(pin "B88"
		)
		(pin "B14"
		)
		(pin "B71"
		)
		(pin "B52"
		)
		(pin "B53"
		)
		(pin "D7"
		)
		(pin "A108"
		)
		(pin "C85"
		)
		(pin "C86"
		)
		(pin "B61"
		)
		(pin "B62"
		)
		(pin "D68"
		)
		(pin "D69"
		)
		(pin "A88"
		)
		(pin "A89"
		)
		(pin "D6"
		)
		(pin "C7"
		)
		(pin "B33"
		)
		(pin "D88"
		)
		(pin "D89"
		)
		(pin "B26"
		)
		(pin "A76"
		)
		(pin "D101"
		)
		(pin "D102"
		)
		(pin "B12"
		)
		(pin "C15"
		)
		(pin "C16"
		)
		(pin "A18"
		)
		(pin "A13"
		)
		(pin "A66"
		)
		(pin "C26"
		)
		(pin "C27"
		)
		(pin "A101"
		)
		(pin "A17"
		)
		(pin "B96"
		)
		(pin "C22"
		)
		(pin "C23"
		)
		(pin "A79"
		)
		(pin "A54"
		)
		(pin "C41"
		)
		(pin "C44"
		)
		(pin "A100"
		)
		(pin "A67"
		)
		(pin "A10"
		)
		(pin "A14"
		)
		(pin "C6"
		)
		(pin "A84"
		)
		(pin "B91"
		)
		(pin "C29"
		)
		(pin "C30"
		)
		(pin "A37"
		)
		(pin "A39"
		)
		(pin "B10"
		)
		(pin "B34"
		)
		(pin "C54"
		)
		(pin "C57"
		)
		(pin "B64"
		)
		(pin "B65"
		)
		(pin "A58"
		)
		(pin "A59"
		)
		(pin "B92"
		)
		(pin "C43"
		)
		(pin "C45"
		)
		(pin "A97"
		)
		(pin "A11"
		)
		(pin "A61"
		)
		(pin "A62"
		)
		(pin "B48"
		)
		(pin "B54"
		)
		(pin "D71"
		)
		(pin "D72"
		)
		(pin "A26"
		)
		(pin "A36"
		)
		(pin "D31"
		)
		(pin "D36"
		)
		(pin "B76"
		)
		(pin "B21"
		)
		(pin "B24"
		)
		(pin "B94"
		)
		(pin "D3"
		)
		(pin "B79"
		)
		(pin "A85"
		)
		(pin "A23"
		)
		(pin "A25"
		)
		(pin "A24"
		)
		(pin "D14"
		)
		(pin "D18"
		)
		(pin "B15"
		)
		(pin "A107"
		)
		(pin "A98"
		)
		(pin "D9"
		)
		(pin "B44"
		)
		(pin "A4"
		)
		(pin "C28"
		)
		(pin "C31"
		)
		(pin "A9"
		)
		(pin "C49"
		)
		(pin "C50"
		)
		(pin "A83"
		)
		(pin "A110"
		)
		(pin "D52"
		)
		(pin "D53"
		)
		(pin "A40"
		)
		(pin "A71"
		)
		(pin "D98"
		)
		(pin "D99"
		)
		(pin "D40"
		)
		(pin "D42"
		)
		(pin "D37"
		)
		(pin "D41"
		)
		(pin "C109"
		)
		(pin "C11"
		)
		(pin "A106"
		)
		(pin "A3"
		)
		(pin "B109"
		)
		(pin "B40"
		)
		(pin "C70"
		)
		(pin "C73"
		)
		(pin "D13"
		)
		(pin "A1"
		)
		(pin "A46"
		)
		(pin "A20"
		)
		(pin "A104"
		)
		(pin "C9"
		)
		(pin "C110"
		)
		(pin "C14"
		)
		(pin "B23"
		)
		(pin "A93"
		)
		(pin "B89"
		)
		(pin "B87"
		)
		(pin "D54"
		)
		(pin "D60"
		)
		(pin "A21"
		)
		(pin "B93"
		)
		(pin "A70"
		)
		(pin "A60"
		)
		(pin "B97"
		)
		(pin "B95"
		)
		(pin "D38"
		)
		(pin "D39"
		)
		(pin "A50"
		)
		(pin "A52"
		)
		(pin "A53"
		)
		(pin "D91"
		)
		(pin "D92"
		)
		(pin "C67"
		)
		(pin "D57"
		)
		(pin "A96"
		)
		(pin "A92"
		)
		(pin "B70"
		)
		(pin "C46"
		)
		(pin "C47"
		)
		(pin "B4"
		)
		(pin "A64"
		)
		(pin "A65"
		)
		(pin "B43"
		)
		(pin "C21"
		)
		(pin "C25"
		)
		(pin "B42"
		)
		(pin "C19"
		)
		(pin "C20"
		)
		(pin "C18"
		)
		(pin "C2"
		)
		(pin "C107"
		)
		(pin "C108"
		)
		(pin "B35"
		)
		(pin "A28"
		)
		(pin "B11"
		)
		(pin "A103"
		)
		(pin "C97"
		)
		(pin "D1"
		)
		(pin "B98"
		)
		(pin "A19"
		)
		(pin "A68"
		)
		(pin "A69"
		)
		(pin "B55"
		)
		(pin "B56"
		)
		(pin "A8"
		)
		(pin "A33"
		)
		(pin "A95"
		)
		(pin "D96"
		)
		(pin "D97"
		)
		(pin "B31"
		)
		(pin "B105"
		)
		(pin "B100"
		)
		(pin "C65"
		)
		(pin "C66"
		)
		(pin "B104"
		)
		(pin "D61"
		)
		(pin "D62"
		)
		(pin "D78"
		)
		(pin "D79"
		)
		(pin "C83"
		)
		(pin "C84"
		)
		(pin "D74"
		)
		(pin "D75"
		)
		(pin "A45"
		)
		(pin "D106"
		)
		(pin "D107"
		)
		(pin "C8"
		)
		(pin "C80"
		)
		(pin "C87"
		)
		(pin "C90"
		)
		(pin "D58"
		)
		(pin "D59"
		)
		(pin "D104"
		)
		(pin "D105"
		)
		(pin "C93"
		)
		(pin "C96"
		)
		(pin "B73"
		)
		(pin "D108"
		)
		(pin "D109"
		)
		(pin "B20"
		)
		(pin "A27"
		)
		(pin "D34"
		)
		(pin "D35"
		)
		(pin "C17"
		)
		(pin "C24"
		)
		(pin "B49"
		)
		(pin "A6"
		)
		(pin "B5"
		)
		(pin "B99"
		)
		(pin "B25"
		)
		(pin "D94"
		)
		(pin "D95"
		)
		(pin "B106"
		)
		(pin "B67"
		)
		(pin "A2"
		)
		(pin "B13"
		)
		(pin "A49"
		)
		(pin "C52"
		)
		(pin "C53"
		)
		(pin "B72"
		)
		(pin "C94"
		)
		(pin "C95"
		)
		(pin "B74"
		)
		(pin "D10"
		)
		(pin "B75"
		)
		(pin "B77"
		)
		(pin "C98"
		)
		(pin "C99"
		)
		(pin "A7"
		)
		(pin "C88"
		)
		(pin "C89"
		)
		(pin "C10"
		)
		(pin "B78"
		)
		(pin "B81"
		)
		(pin "B28"
		)
		(pin "A63"
		)
		(pin "C76"
		)
		(pin "C77"
		)
		(pin "A55"
		)
		(pin "A56"
		)
		(pin "C48"
		)
		(pin "C5"
		)
		(pin "A5"
		)
		(pin "C1"
		)
		(pin "C100"
		)
		(pin "B47"
		)
		(pin "C74"
		)
		(pin "C75"
		)
		(pin "C12"
		)
		(pin "B80"
		)
		(pin "D15"
		)
		(pin "D16"
		)
		(pin "D100"
		)
		(pin "D103"
		)
		(pin "B2"
		)
		(pin "B9"
		)
		(pin "A94"
		)
		(pin "B82"
		)
		(pin "D25"
		)
		(pin "D28"
		)
		(pin "B16"
		)
		(pin "D65"
		)
		(pin "D66"
		)
		(pin "D32"
		)
		(pin "D33"
		)
		(pin "B8"
		)
		(pin "B60"
		)
		(pin "A38"
		)
		(pin "A73"
		)
		(pin "A80"
		)
		(pin "B18"
		)
		(pin "MP"
		)
		(instances
			(project "com-express-7-baseboard"
				(path ""
					(reference "J12")
					(unit 13)
				)
			)
		)
	)
	(symbol
		(lib_id "antmicroResistors0402:R_10k_0402")
		(at 256.54 138.43 90)
		(unit 1)
		(exclude_from_sim no)
		(in_bom yes)
		(on_board yes)
		(dnp no)
		(property "Reference" "R168"
			(at 257.81 134.62 90)
			(effects
				(font
					(size 1.27 1.27)
					(thickness 0.15)
				)
				(justify right)
			)
		)
		(property "Value" "R_10k_0402"
			(at 269.24 118.11 0)
			(effects
				(font
					(size 1.27 1.27)
					(thickness 0.15)
				)
				(justify left bottom)
				(hide yes)
			)
		)
		(property "Footprint" "antmicro-footprints:R_0402_1005Metric"
			(at 271.78 118.11 0)
			(effects
				(font
					(size 1.27 1.27)
					(thickness 0.15)
				)
				(justify left bottom)
				(hide yes)
			)
		)
		(property "Datasheet" "https://www.bourns.com/docs/product-datasheets/cr.pdf"
			(at 274.32 118.11 0)
			(effects
				(font
					(size 1.27 1.27)
					(thickness 0.15)
				)
				(justify left bottom)
				(hide yes)
			)
		)
		(property "Description" ""
			(at 256.54 138.43 0)
			(effects
				(font
					(size 1.27 1.27)
				)
				(hide yes)
			)
		)
		(property "MPN" "CR0402-FX-1002GLF"
			(at 276.86 118.11 0)
			(effects
				(font
					(size 1.27 1.27)
					(thickness 0.15)
				)
				(justify left bottom)
				(hide yes)
			)
		)
		(property "Manufacturer" "Bourns"
			(at 279.4 118.11 0)
			(effects
				(font
					(size 1.27 1.27)
					(thickness 0.15)
				)
				(justify left bottom)
				(hide yes)
			)
		)
		(property "License" "Apache-2.0"
			(at 281.94 118.11 0)
			(effects
				(font
					(size 1.27 1.27)
					(thickness 0.15)
				)
				(justify left bottom)
				(hide yes)
			)
		)
		(property "Author" "Antmicro"
			(at 284.48 118.11 0)
			(effects
				(font
					(size 1.27 1.27)
					(thickness 0.15)
				)
				(justify left bottom)
				(hide yes)
			)
		)
		(property "Val" "10k"
			(at 257.81 137.16 90)
			(effects
				(font
					(size 1.27 1.27)
					(thickness 0.15)
				)
				(justify right)
			)
		)
		(property "Tolerance" "1%"
			(at 266.7 118.11 0)
			(effects
				(font
					(size 1.27 1.27)
				)
				(justify left bottom)
				(hide yes)
			)
		)
		(property "Public" "False"
			(at 287.02 118.11 0)
			(effects
				(font
					(size 1.27 1.27)
				)
				(justify left bottom)
				(hide yes)
			)
		)
		(pin "1"
		)
		(pin "2"
		)
		(instances
			(project "com-express-7-baseboard"
				(path ""
					(reference "R168")
					(unit 1)
				)
			)
		)
	)
	(symbol
		(lib_id "antmicroGenericPinHeaders:PinHeader_1x3_P2.54mm_Drill1.1mm")
		(at 363.22 237.49 0)
		(unit 1)
		(exclude_from_sim no)
		(in_bom yes)
		(on_board yes)
		(dnp no)
		(fields_autoplaced yes)
		(property "Reference" "J14"
			(at 369.57 238.7599 0)
			(effects
				(font
					(size 1.27 1.27)
					(thickness 0.15)
				)
				(justify left)
			)
		)
		(property "Value" "PinHeader_1x3_P2.54mm_Drill1.1mm"
			(at 383.54 247.65 0)
			(effects
				(font
					(size 1.27 1.27)
					(thickness 0.15)
				)
				(justify left bottom)
				(hide yes)
			)
		)
		(property "Footprint" "antmicro-footprints:PinHeader_1x3_P2.54mm_Drill1.1mm"
			(at 383.54 250.19 0)
			(effects
				(font
					(size 1.27 1.27)
					(thickness 0.15)
				)
				(justify left bottom)
				(hide yes)
			)
		)
		(property "Datasheet" "https://katalog.we-online.de/em/datasheet/6130xx11121.pdf"
			(at 383.54 252.73 0)
			(effects
				(font
					(size 1.27 1.27)
					(thickness 0.15)
				)
				(justify left bottom)
				(hide yes)
			)
		)
		(property "Description" ""
			(at 363.22 237.49 0)
			(effects
				(font
					(size 1.27 1.27)
				)
				(hide yes)
			)
		)
		(property "MPN" "61300311121"
			(at 369.57 241.2999 0)
			(effects
				(font
					(size 1.27 1.27)
					(thickness 0.15)
				)
				(justify left)
			)
		)
		(property "Manufacturer" "Würth Elektronik"
			(at 383.54 255.27 0)
			(effects
				(font
					(size 1.27 1.27)
					(thickness 0.15)
				)
				(justify left bottom)
				(hide yes)
			)
		)
		(property "Author" "Antmicro"
			(at 383.54 260.35 0)
			(effects
				(font
					(size 1.27 1.27)
					(thickness 0.15)
				)
				(justify left bottom)
				(hide yes)
			)
		)
		(property "License" "Apache-2.0"
			(at 383.54 262.89 0)
			(effects
				(font
					(size 1.27 1.27)
					(thickness 0.15)
				)
				(justify left bottom)
				(hide yes)
			)
		)
		(pin "3"
		)
		(pin "2"
		)
		(pin "1"
		)
		(instances
			(project "com-express-7-baseboard"
				(path ""
					(reference "J14")
					(unit 1)
				)
			)
		)
	)
	(symbol
		(lib_id "antmicropower:+3V3_AON")
		(at 116.84 120.65 0)
		(unit 1)
		(exclude_from_sim no)
		(in_bom yes)
		(on_board yes)
		(dnp no)
		(property "Reference" "#PWR0236"
			(at 116.84 124.46 0)
			(effects
				(font
					(size 1.27 1.27)
				)
				(hide yes)
			)
		)
		(property "Value" "+3V3_AON"
			(at 116.84 116.84 0)
			(effects
				(font
					(size 1.27 1.27)
				)
			)
		)
		(property "Footprint" ""
			(at 116.84 120.65 0)
			(effects
				(font
					(size 1.27 1.27)
				)
				(hide yes)
			)
		)
		(property "Datasheet" ""
			(at 116.84 120.65 0)
			(effects
				(font
					(size 1.27 1.27)
				)
				(hide yes)
			)
		)
		(property "Description" ""
			(at 116.84 120.65 0)
			(effects
				(font
					(size 1.27 1.27)
				)
				(hide yes)
			)
		)
		(pin "1"
		)
		(instances
			(project "com-express-7-baseboard"
				(path ""
					(reference "#PWR0236")
					(unit 1)
				)
			)
		)
	)
	(symbol
		(lib_id "antmicropower:GND")
		(at 218.44 86.36 0)
		(unit 1)
		(exclude_from_sim no)
		(in_bom yes)
		(on_board yes)
		(dnp no)
		(property "Reference" "#PWR0242"
			(at 227.33 88.9 0)
			(effects
				(font
					(size 1.27 1.27)
					(thickness 0.15)
				)
				(justify left bottom)
				(hide yes)
			)
		)
		(property "Value" "GND"
			(at 218.44 90.17 0)
			(effects
				(font
					(size 1.27 1.27)
					(thickness 0.15)
				)
			)
		)
		(property "Footprint" ""
			(at 227.33 93.98 0)
			(effects
				(font
					(size 1.27 1.27)
					(thickness 0.15)
				)
				(justify left bottom)
				(hide yes)
			)
		)
		(property "Datasheet" ""
			(at 227.33 99.06 0)
			(effects
				(font
					(size 1.27 1.27)
					(thickness 0.15)
				)
				(justify left bottom)
				(hide yes)
			)
		)
		(property "Description" ""
			(at 218.44 86.36 0)
			(effects
				(font
					(size 1.27 1.27)
				)
				(hide yes)
			)
		)
		(property "Author" "Antmicro"
			(at 227.33 93.98 0)
			(effects
				(font
					(size 1.27 1.27)
					(thickness 0.15)
				)
				(justify left bottom)
				(hide yes)
			)
		)
		(property "License" "Apache-2.0"
			(at 227.33 96.52 0)
			(effects
				(font
					(size 1.27 1.27)
					(thickness 0.15)
				)
				(justify left bottom)
				(hide yes)
			)
		)
		(pin "1"
		)
		(instances
			(project "com-express-7-baseboard"
				(path ""
					(reference "#PWR0242")
					(unit 1)
				)
			)
		)
	)
	(symbol
		(lib_id "antmicroCapacitors0603:C_22u_16V_0603")
		(at 93.98 45.72 270)
		(mirror x)
		(unit 1)
		(exclude_from_sim no)
		(in_bom yes)
		(on_board yes)
		(dnp no)
		(fields_autoplaced yes)
		(property "Reference" "C93"
			(at 91.44 41.9036 90)
			(effects
				(font
					(size 1.27 1.27)
					(thickness 0.15)
				)
				(justify right)
			)
		)
		(property "Value" "C_22u_16V_0603"
			(at 83.82 25.4 0)
			(effects
				(font
					(size 1.27 1.27)
					(thickness 0.15)
				)
				(justify left bottom)
				(hide yes)
			)
		)
		(property "Footprint" "antmicro-footprints:C_0603_1608Metric"
			(at 81.28 25.4 0)
			(effects
				(font
					(size 1.27 1.27)
					(thickness 0.15)
				)
				(justify left bottom)
				(hide yes)
			)
		)
		(property "Datasheet" "https://product.samsungsem.com/mlcc/CL10A226MO7JZN.do"
			(at 78.74 25.4 0)
			(effects
				(font
					(size 1.27 1.27)
					(thickness 0.15)
				)
				(justify left bottom)
				(hide yes)
			)
		)
		(property "Description" ""
			(at 93.98 45.72 0)
			(effects
				(font
					(size 1.27 1.27)
				)
				(hide yes)
			)
		)
		(property "MPN" "CL10A226MO7JZNC"
			(at 76.2 25.4 0)
			(effects
				(font
					(size 1.27 1.27)
					(thickness 0.15)
				)
				(justify left bottom)
				(hide yes)
			)
		)
		(property "Manufacturer" "Samsung Electro-Mechanics"
			(at 73.66 25.4 0)
			(effects
				(font
					(size 1.27 1.27)
					(thickness 0.15)
				)
				(justify left bottom)
				(hide yes)
			)
		)
		(property "License" "Apache-2.0"
			(at 71.12 25.4 0)
			(effects
				(font
					(size 1.27 1.27)
					(thickness 0.15)
				)
				(justify left bottom)
				(hide yes)
			)
		)
		(property "Author" "Antmicro"
			(at 68.58 25.4 0)
			(effects
				(font
					(size 1.27 1.27)
					(thickness 0.15)
				)
				(justify left bottom)
				(hide yes)
			)
		)
		(property "Val" "22u"
			(at 91.44 44.4436 90)
			(effects
				(font
					(size 1.27 1.27)
					(thickness 0.15)
				)
				(justify right)
			)
		)
		(property "Voltage" "16V"
			(at 91.44 45.7135 90)
			(effects
				(font
					(size 1.27 1.27)
				)
				(justify right)
				(hide yes)
			)
		)
		(property "Dielectric" ""
			(at 63.5 25.4 0)
			(effects
				(font
					(size 1.27 1.27)
				)
				(justify left bottom)
				(hide yes)
			)
		)
		(property "Public" "False"
			(at 60.96 25.4 0)
			(effects
				(font
					(size 1.27 1.27)
				)
				(justify left bottom)
				(hide yes)
			)
		)
		(pin "2"
		)
		(pin "1"
		)
		(instances
			(project "com-express-7-baseboard"
				(path ""
					(reference "C93")
					(unit 1)
				)
			)
		)
	)
	(symbol
		(lib_id "antmicroB2BConnectors:Plug_Bus_CE7_EPT_401-51501-51")
		(at 76.2 66.04 0)
		(unit 8)
		(exclude_from_sim no)
		(in_bom yes)
		(on_board yes)
		(dnp no)
		(fields_autoplaced yes)
		(property "Reference" "J12"
			(at 57.15 58.42 0)
			(effects
				(font
					(size 1.27 1.27)
					(thickness 0.15)
				)
			)
		)
		(property "Value" "Plug_Bus_CE7_EPT_401-51501-51"
			(at 129.54 78.74 0)
			(effects
				(font
					(size 1.27 1.27)
					(thickness 0.15)
				)
				(justify left bottom)
				(hide yes)
			)
		)
		(property "Footprint" "antmicro-footprints:EPT_401-51501-51"
			(at 129.54 81.28 0)
			(effects
				(font
					(size 1.27 1.27)
					(thickness 0.15)
				)
				(justify left bottom)
				(hide yes)
			)
		)
		(property "Datasheet" "https://www.farnell.com/datasheets/1905093.pdf"
			(at 129.54 83.82 0)
			(effects
				(font
					(size 1.27 1.27)
					(thickness 0.15)
				)
				(justify left bottom)
				(hide yes)
			)
		)
		(property "Description" ""
			(at 76.2 66.04 0)
			(effects
				(font
					(size 1.27 1.27)
				)
				(hide yes)
			)
		)
		(property "Author" "Antmicro"
			(at 129.54 86.36 0)
			(effects
				(font
					(size 1.27 1.27)
					(thickness 0.15)
				)
				(justify left bottom)
				(hide yes)
			)
		)
		(property "License" "Apache-2.0"
			(at 129.54 88.9 0)
			(effects
				(font
					(size 1.27 1.27)
					(thickness 0.15)
				)
				(justify left bottom)
				(hide yes)
			)
		)
		(property "Manufacturer" "ept"
			(at 129.54 71.12 0)
			(effects
				(font
					(size 1.27 1.27)
					(thickness 0.15)
				)
				(justify left bottom)
				(hide yes)
			)
		)
		(property "MPN" "401-51501-51"
			(at 57.15 60.96 0)
			(effects
				(font
					(size 1.27 1.27)
					(thickness 0.15)
				)
			)
		)
		(pin "C91"
		)
		(pin "C92"
		)
		(pin "A15"
		)
		(pin "A91"
		)
		(pin "C34"
		)
		(pin "C35"
		)
		(pin "D22"
		)
		(pin "D23"
		)
		(pin "D55"
		)
		(pin "D56"
		)
		(pin "C55"
		)
		(pin "C56"
		)
		(pin "C71"
		)
		(pin "C72"
		)
		(pin "C32"
		)
		(pin "C33"
		)
		(pin "B6"
		)
		(pin "B58"
		)
		(pin "B59"
		)
		(pin "D5"
		)
		(pin "D51"
		)
		(pin "A29"
		)
		(pin "D46"
		)
		(pin "D47"
		)
		(pin "C105"
		)
		(pin "C106"
		)
		(pin "A16"
		)
		(pin "B22"
		)
		(pin "B51"
		)
		(pin "B30"
		)
		(pin "A44"
		)
		(pin "C51"
		)
		(pin "C60"
		)
		(pin "A81"
		)
		(pin "A82"
		)
		(pin "D90"
		)
		(pin "D93"
		)
		(pin "B68"
		)
		(pin "B69"
		)
		(pin "C103"
		)
		(pin "C104"
		)
		(pin "C58"
		)
		(pin "C59"
		)
		(pin "D84"
		)
		(pin "D87"
		)
		(pin "A30"
		)
		(pin "B29"
		)
		(pin "A41"
		)
		(pin "C40"
		)
		(pin "C42"
		)
		(pin "D80"
		)
		(pin "D83"
		)
		(pin "B103"
		)
		(pin "A102"
		)
		(pin "C101"
		)
		(pin "C102"
		)
		(pin "D11"
		)
		(pin "D110"
		)
		(pin "B37"
		)
		(pin "B45"
		)
		(pin "C61"
		)
		(pin "C62"
		)
		(pin "A42"
		)
		(pin "B36"
		)
		(pin "B57"
		)
		(pin "D12"
		)
		(pin "D44"
		)
		(pin "D48"
		)
		(pin "B32"
		)
		(pin "B107"
		)
		(pin "B108"
		)
		(pin "B110"
		)
		(pin "B101"
		)
		(pin "C63"
		)
		(pin "C64"
		)
		(pin "B50"
		)
		(pin "A87"
		)
		(pin "A86"
		)
		(pin "B27"
		)
		(pin "D17"
		)
		(pin "D24"
		)
		(pin "D26"
		)
		(pin "D27"
		)
		(pin "A47"
		)
		(pin "C81"
		)
		(pin "C82"
		)
		(pin "C68"
		)
		(pin "C69"
		)
		(pin "A74"
		)
		(pin "A48"
		)
		(pin "A57"
		)
		(pin "A43"
		)
		(pin "A31"
		)
		(pin "D29"
		)
		(pin "D30"
		)
		(pin "C36"
		)
		(pin "C37"
		)
		(pin "C3"
		)
		(pin "A35"
		)
		(pin "A34"
		)
		(pin "B7"
		)
		(pin "B46"
		)
		(pin "B1"
		)
		(pin "B63"
		)
		(pin "A51"
		)
		(pin "A99"
		)
		(pin "B17"
		)
		(pin "C13"
		)
		(pin "C4"
		)
		(pin "B102"
		)
		(pin "C38"
		)
		(pin "C39"
		)
		(pin "B3"
		)
		(pin "A90"
		)
		(pin "A72"
		)
		(pin "B84"
		)
		(pin "D19"
		)
		(pin "D20"
		)
		(pin "D43"
		)
		(pin "D45"
		)
		(pin "A77"
		)
		(pin "A78"
		)
		(pin "B38"
		)
		(pin "B86"
		)
		(pin "D77"
		)
		(pin "D8"
		)
		(pin "A32"
		)
		(pin "B85"
		)
		(pin "D73"
		)
		(pin "D76"
		)
		(pin "D63"
		)
		(pin "D64"
		)
		(pin "D67"
		)
		(pin "D70"
		)
		(pin "B83"
		)
		(pin "D81"
		)
		(pin "D82"
		)
		(pin "B41"
		)
		(pin "D49"
		)
		(pin "D50"
		)
		(pin "A75"
		)
		(pin "D2"
		)
		(pin "D21"
		)
		(pin "C78"
		)
		(pin "C79"
		)
		(pin "B19"
		)
		(pin "B39"
		)
		(pin "A12"
		)
		(pin "B66"
		)
		(pin "D4"
		)
		(pin "D85"
		)
		(pin "D86"
		)
		(pin "A105"
		)
		(pin "B90"
		)
		(pin "A22"
		)
		(pin "A109"
		)
		(pin "B88"
		)
		(pin "B14"
		)
		(pin "B71"
		)
		(pin "B52"
		)
		(pin "B53"
		)
		(pin "D7"
		)
		(pin "A108"
		)
		(pin "C85"
		)
		(pin "C86"
		)
		(pin "B61"
		)
		(pin "B62"
		)
		(pin "D68"
		)
		(pin "D69"
		)
		(pin "A88"
		)
		(pin "A89"
		)
		(pin "D6"
		)
		(pin "C7"
		)
		(pin "B33"
		)
		(pin "D88"
		)
		(pin "D89"
		)
		(pin "B26"
		)
		(pin "A76"
		)
		(pin "D101"
		)
		(pin "D102"
		)
		(pin "B12"
		)
		(pin "C15"
		)
		(pin "C16"
		)
		(pin "A18"
		)
		(pin "A13"
		)
		(pin "A66"
		)
		(pin "C26"
		)
		(pin "C27"
		)
		(pin "A101"
		)
		(pin "A17"
		)
		(pin "B96"
		)
		(pin "C22"
		)
		(pin "C23"
		)
		(pin "A79"
		)
		(pin "A54"
		)
		(pin "C41"
		)
		(pin "C44"
		)
		(pin "A100"
		)
		(pin "A67"
		)
		(pin "A10"
		)
		(pin "A14"
		)
		(pin "C6"
		)
		(pin "A84"
		)
		(pin "B91"
		)
		(pin "C29"
		)
		(pin "C30"
		)
		(pin "A37"
		)
		(pin "A39"
		)
		(pin "B10"
		)
		(pin "B34"
		)
		(pin "C54"
		)
		(pin "C57"
		)
		(pin "B64"
		)
		(pin "B65"
		)
		(pin "A58"
		)
		(pin "A59"
		)
		(pin "B92"
		)
		(pin "C43"
		)
		(pin "C45"
		)
		(pin "A97"
		)
		(pin "A11"
		)
		(pin "A61"
		)
		(pin "A62"
		)
		(pin "B48"
		)
		(pin "B54"
		)
		(pin "D71"
		)
		(pin "D72"
		)
		(pin "A26"
		)
		(pin "A36"
		)
		(pin "D31"
		)
		(pin "D36"
		)
		(pin "B76"
		)
		(pin "B21"
		)
		(pin "B24"
		)
		(pin "B94"
		)
		(pin "D3"
		)
		(pin "B79"
		)
		(pin "A85"
		)
		(pin "A23"
		)
		(pin "A25"
		)
		(pin "A24"
		)
		(pin "D14"
		)
		(pin "D18"
		)
		(pin "B15"
		)
		(pin "A107"
		)
		(pin "A98"
		)
		(pin "D9"
		)
		(pin "B44"
		)
		(pin "A4"
		)
		(pin "C28"
		)
		(pin "C31"
		)
		(pin "A9"
		)
		(pin "C49"
		)
		(pin "C50"
		)
		(pin "A83"
		)
		(pin "A110"
		)
		(pin "D52"
		)
		(pin "D53"
		)
		(pin "A40"
		)
		(pin "A71"
		)
		(pin "D98"
		)
		(pin "D99"
		)
		(pin "D40"
		)
		(pin "D42"
		)
		(pin "D37"
		)
		(pin "D41"
		)
		(pin "C109"
		)
		(pin "C11"
		)
		(pin "A106"
		)
		(pin "A3"
		)
		(pin "B109"
		)
		(pin "B40"
		)
		(pin "C70"
		)
		(pin "C73"
		)
		(pin "D13"
		)
		(pin "A1"
		)
		(pin "A46"
		)
		(pin "A20"
		)
		(pin "A104"
		)
		(pin "C9"
		)
		(pin "C110"
		)
		(pin "C14"
		)
		(pin "B23"
		)
		(pin "A93"
		)
		(pin "B89"
		)
		(pin "B87"
		)
		(pin "D54"
		)
		(pin "D60"
		)
		(pin "A21"
		)
		(pin "B93"
		)
		(pin "A70"
		)
		(pin "A60"
		)
		(pin "B97"
		)
		(pin "B95"
		)
		(pin "D38"
		)
		(pin "D39"
		)
		(pin "A50"
		)
		(pin "A52"
		)
		(pin "A53"
		)
		(pin "D91"
		)
		(pin "D92"
		)
		(pin "C67"
		)
		(pin "D57"
		)
		(pin "A96"
		)
		(pin "A92"
		)
		(pin "B70"
		)
		(pin "C46"
		)
		(pin "C47"
		)
		(pin "B4"
		)
		(pin "A64"
		)
		(pin "A65"
		)
		(pin "B43"
		)
		(pin "C21"
		)
		(pin "C25"
		)
		(pin "B42"
		)
		(pin "C19"
		)
		(pin "C20"
		)
		(pin "C18"
		)
		(pin "C2"
		)
		(pin "C107"
		)
		(pin "C108"
		)
		(pin "B35"
		)
		(pin "A28"
		)
		(pin "B11"
		)
		(pin "A103"
		)
		(pin "C97"
		)
		(pin "D1"
		)
		(pin "B98"
		)
		(pin "A19"
		)
		(pin "A68"
		)
		(pin "A69"
		)
		(pin "B55"
		)
		(pin "B56"
		)
		(pin "A8"
		)
		(pin "A33"
		)
		(pin "A95"
		)
		(pin "D96"
		)
		(pin "D97"
		)
		(pin "B31"
		)
		(pin "B105"
		)
		(pin "B100"
		)
		(pin "C65"
		)
		(pin "C66"
		)
		(pin "B104"
		)
		(pin "D61"
		)
		(pin "D62"
		)
		(pin "D78"
		)
		(pin "D79"
		)
		(pin "C83"
		)
		(pin "C84"
		)
		(pin "D74"
		)
		(pin "D75"
		)
		(pin "A45"
		)
		(pin "D106"
		)
		(pin "D107"
		)
		(pin "C8"
		)
		(pin "C80"
		)
		(pin "C87"
		)
		(pin "C90"
		)
		(pin "D58"
		)
		(pin "D59"
		)
		(pin "D104"
		)
		(pin "D105"
		)
		(pin "C93"
		)
		(pin "C96"
		)
		(pin "B73"
		)
		(pin "D108"
		)
		(pin "D109"
		)
		(pin "B20"
		)
		(pin "A27"
		)
		(pin "D34"
		)
		(pin "D35"
		)
		(pin "C17"
		)
		(pin "C24"
		)
		(pin "B49"
		)
		(pin "A6"
		)
		(pin "B5"
		)
		(pin "B99"
		)
		(pin "B25"
		)
		(pin "D94"
		)
		(pin "D95"
		)
		(pin "B106"
		)
		(pin "B67"
		)
		(pin "A2"
		)
		(pin "B13"
		)
		(pin "A49"
		)
		(pin "C52"
		)
		(pin "C53"
		)
		(pin "B72"
		)
		(pin "C94"
		)
		(pin "C95"
		)
		(pin "B74"
		)
		(pin "D10"
		)
		(pin "B75"
		)
		(pin "B77"
		)
		(pin "C98"
		)
		(pin "C99"
		)
		(pin "A7"
		)
		(pin "C88"
		)
		(pin "C89"
		)
		(pin "C10"
		)
		(pin "B78"
		)
		(pin "B81"
		)
		(pin "B28"
		)
		(pin "A63"
		)
		(pin "C76"
		)
		(pin "C77"
		)
		(pin "A55"
		)
		(pin "A56"
		)
		(pin "C48"
		)
		(pin "C5"
		)
		(pin "A5"
		)
		(pin "C1"
		)
		(pin "C100"
		)
		(pin "B47"
		)
		(pin "C74"
		)
		(pin "C75"
		)
		(pin "C12"
		)
		(pin "B80"
		)
		(pin "D15"
		)
		(pin "D16"
		)
		(pin "D100"
		)
		(pin "D103"
		)
		(pin "B2"
		)
		(pin "B9"
		)
		(pin "A94"
		)
		(pin "B82"
		)
		(pin "D25"
		)
		(pin "D28"
		)
		(pin "B16"
		)
		(pin "D65"
		)
		(pin "D66"
		)
		(pin "D32"
		)
		(pin "D33"
		)
		(pin "B8"
		)
		(pin "B60"
		)
		(pin "A38"
		)
		(pin "A73"
		)
		(pin "A80"
		)
		(pin "B18"
		)
		(pin "MP"
		)
		(instances
			(project "com-express-7-baseboard"
				(path ""
					(reference "J12")
					(unit 8)
				)
			)
		)
	)
	(symbol
		(lib_id "antmicroResistors0402:R_0R_0402")
		(at 265.43 68.58 180)
		(unit 1)
		(exclude_from_sim no)
		(in_bom yes)
		(on_board yes)
		(dnp no)
		(property "Reference" "R174"
			(at 257.81 67.31 0)
			(effects
				(font
					(size 1.27 1.27)
					(thickness 0.15)
				)
			)
		)
		(property "Value" "R_0R_0402"
			(at 245.11 55.88 0)
			(effects
				(font
					(size 1.27 1.27)
					(thickness 0.15)
				)
				(justify left bottom)
				(hide yes)
			)
		)
		(property "Footprint" "antmicro-footprints:R_0402_1005Metric"
			(at 245.11 53.34 0)
			(effects
				(font
					(size 1.27 1.27)
					(thickness 0.15)
				)
				(justify left bottom)
				(hide yes)
			)
		)
		(property "Datasheet" "https://industrial.panasonic.com/cdbs/www-data/pdf/RDA0000/AOA0000C301.pdf"
			(at 245.11 50.8 0)
			(effects
				(font
					(size 1.27 1.27)
					(thickness 0.15)
				)
				(justify left bottom)
				(hide yes)
			)
		)
		(property "Description" ""
			(at 265.43 68.58 0)
			(effects
				(font
					(size 1.27 1.27)
				)
				(hide yes)
			)
		)
		(property "MPN" "ERJ2GE0R00X"
			(at 245.11 48.26 0)
			(effects
				(font
					(size 1.27 1.27)
					(thickness 0.15)
				)
				(justify left bottom)
				(hide yes)
			)
		)
		(property "Manufacturer" "Panasonic"
			(at 245.11 45.72 0)
			(effects
				(font
					(size 1.27 1.27)
					(thickness 0.15)
				)
				(justify left bottom)
				(hide yes)
			)
		)
		(property "License" "Apache-2.0"
			(at 245.11 43.18 0)
			(effects
				(font
					(size 1.27 1.27)
					(thickness 0.15)
				)
				(justify left bottom)
				(hide yes)
			)
		)
		(property "Author" "Antmicro"
			(at 245.11 40.64 0)
			(effects
				(font
					(size 1.27 1.27)
					(thickness 0.15)
				)
				(justify left bottom)
				(hide yes)
			)
		)
		(property "Val" "0R"
			(at 266.7 67.31 0)
			(effects
				(font
					(size 1.27 1.27)
					(thickness 0.15)
				)
			)
		)
		(property "Tolerance" "~"
			(at 245.11 58.42 0)
			(effects
				(font
					(size 1.27 1.27)
				)
				(justify left bottom)
				(hide yes)
			)
		)
		(property "Current" "1A"
			(at 245.11 38.1 0)
			(effects
				(font
					(size 1.27 1.27)
					(thickness 0.15)
				)
				(justify left bottom)
				(hide yes)
			)
		)
		(property "Public" "False"
			(at 245.11 38.1 0)
			(effects
				(font
					(size 1.27 1.27)
				)
				(justify left bottom)
				(hide yes)
			)
		)
		(pin "1"
		)
		(pin "2"
		)
		(instances
			(project "com-express-7-baseboard"
				(path ""
					(reference "R174")
					(unit 1)
				)
			)
		)
	)
	(symbol
		(lib_id "antmicroShuntsJumpers:Jumper_1x2_P2.54mm")
		(at 151.13 62.23 0)
		(unit 1)
		(exclude_from_sim no)
		(in_bom yes)
		(on_board yes)
		(dnp no)
		(fields_autoplaced yes)
		(property "Reference" "JP1"
			(at 154.94 63.5 0)
			(effects
				(font
					(size 1.27 1.27)
				)
				(justify left)
			)
		)
		(property "Value" "Jumper_1x2_P2.54mm"
			(at 154.94 66.04 0)
			(effects
				(font
					(size 1.27 1.27)
				)
				(justify left)
			)
		)
		(property "Footprint" "antmicro-footprints:Jumper_1x2_P2.54mm"
			(at 151.13 64.77 0)
			(effects
				(font
					(size 1.27 1.27)
				)
				(hide yes)
			)
		)
		(property "Datasheet" "https://www.tme.eu/en/details/jumper-w/pin-headers/ninigi/"
			(at 151.13 62.23 0)
			(effects
				(font
					(size 1.27 1.27)
				)
				(hide yes)
			)
		)
		(property "Description" ""
			(at 151.13 62.23 0)
			(effects
				(font
					(size 1.27 1.27)
				)
				(hide yes)
			)
		)
		(property "MPN" "JUMPER-W"
			(at 151.13 67.31 0)
			(effects
				(font
					(size 1.27 1.27)
				)
				(hide yes)
			)
		)
		(property "Manufacturer" "Ninigi"
			(at 151.13 69.215 0)
			(effects
				(font
					(size 1.27 1.27)
				)
				(hide yes)
			)
		)
		(property "License" "Apache-2.0"
			(at 151.13 73.025 0)
			(effects
				(font
					(size 1.27 1.27)
				)
				(hide yes)
			)
		)
		(property "Author" "Antmicro"
			(at 151.13 71.12 0)
			(effects
				(font
					(size 1.27 1.27)
				)
				(hide yes)
			)
		)
		(instances
			(project "com-express-7-baseboard"
				(path ""
					(reference "JP1")
					(unit 1)
				)
			)
		)
	)
	(symbol
		(lib_id "antmicroPushbuttonSwitches:SW_1-1825027-1_THT")
		(at 218.44 73.66 270)
		(unit 1)
		(exclude_from_sim no)
		(in_bom yes)
		(on_board yes)
		(dnp no)
		(fields_autoplaced yes)
		(property "Reference" "SW1"
			(at 214.63 77.4699 90)
			(effects
				(font
					(size 1.27 1.27)
					(thickness 0.15)
				)
				(justify right)
			)
		)
		(property "Value" "SW_1-1825027-1_THT"
			(at 210.82 99.06 0)
			(effects
				(font
					(size 1.27 1.27)
					(thickness 0.15)
				)
				(justify left bottom)
				(hide yes)
			)
		)
		(property "Footprint" "antmicro-footprints:SW_1-1825027-1_THT"
			(at 208.28 99.06 0)
			(effects
				(font
					(size 1.27 1.27)
					(thickness 0.15)
				)
				(justify left bottom)
				(hide yes)
			)
		)
		(property "Datasheet" "https://www.te.com/commerce/DocumentDelivery/DDEController?Action=showdoc&DocId=Customer+Drawing%7F1825027%7FH1%7Fpdf%7FEnglish%7FENG_CD_1825027_H1.pdf%7F1-1825027-1"
			(at 205.74 99.06 0)
			(effects
				(font
					(size 1.27 1.27)
					(thickness 0.15)
				)
				(justify left bottom)
				(hide yes)
			)
		)
		(property "Description" ""
			(at 218.44 73.66 0)
			(effects
				(font
					(size 1.27 1.27)
				)
				(hide yes)
			)
		)
		(property "MPN" "1-1825027-1"
			(at 214.63 80.0099 90)
			(effects
				(font
					(size 1.27 1.27)
					(thickness 0.15)
				)
				(justify right)
			)
		)
		(property "Manufacturer" "TE Connectivity"
			(at 200.66 99.06 0)
			(effects
				(font
					(size 1.27 1.27)
					(thickness 0.15)
				)
				(justify left bottom)
				(hide yes)
			)
		)
		(property "Author" "Antmicro"
			(at 198.12 99.06 0)
			(effects
				(font
					(size 1.27 1.27)
					(thickness 0.15)
				)
				(justify left bottom)
				(hide yes)
			)
		)
		(property "License" "Apache-2.0"
			(at 195.58 99.06 0)
			(effects
				(font
					(size 1.27 1.27)
					(thickness 0.15)
				)
				(justify left bottom)
				(hide yes)
			)
		)
		(pin "1"
		)
		(pin "2"
		)
		(pin "SH"
		)
		(instances
			(project "com-express-7-baseboard"
				(path ""
					(reference "SW1")
					(unit 1)
				)
			)
		)
	)
	(symbol
		(lib_id "antmicropower:PWR_FLAG")
		(at 382.27 193.04 0)
		(unit 1)
		(exclude_from_sim no)
		(in_bom yes)
		(on_board yes)
		(dnp no)
		(fields_autoplaced yes)
		(property "Reference" "#FLG017"
			(at 382.27 191.135 0)
			(effects
				(font
					(size 1.27 1.27)
				)
				(hide yes)
			)
		)
		(property "Value" "PWR_FLAG"
			(at 382.27 187.96 0)
			(effects
				(font
					(size 1.27 1.27)
				)
			)
		)
		(property "Footprint" ""
			(at 382.27 193.04 0)
			(effects
				(font
					(size 1.27 1.27)
				)
				(hide yes)
			)
		)
		(property "Datasheet" ""
			(at 382.27 193.04 0)
			(effects
				(font
					(size 1.27 1.27)
				)
				(hide yes)
			)
		)
		(property "Description" ""
			(at 382.27 193.04 0)
			(effects
				(font
					(size 1.27 1.27)
				)
				(hide yes)
			)
		)
		(pin "1"
		)
		(instances
			(project "com-express-7-baseboard"
				(path ""
					(reference "#FLG017")
					(unit 1)
				)
			)
		)
	)
	(symbol
		(lib_id "antmicroTestPoints:TP_0.75mm_SMD")
		(at 76.2 124.46 0)
		(unit 1)
		(exclude_from_sim no)
		(in_bom no)
		(on_board yes)
		(dnp no)
		(fields_autoplaced yes)
		(property "Reference" "TP29"
			(at 81.28 124.46 0)
			(effects
				(font
					(size 1.27 1.27)
					(thickness 0.15)
				)
				(justify left)
			)
		)
		(property "Value" "TP_0.75mm_SMD"
			(at 86.995 128.27 0)
			(effects
				(font
					(size 1.27 1.27)
					(thickness 0.15)
				)
				(justify left bottom)
				(hide yes)
			)
		)
		(property "Footprint" "antmicro-footprints:TP_SMD_0.75mm"
			(at 86.995 130.81 0)
			(effects
				(font
					(size 1.27 1.27)
					(thickness 0.15)
				)
				(justify left bottom)
				(hide yes)
			)
		)
		(property "Datasheet" ""
			(at 93.98 137.16 0)
			(effects
				(font
					(size 1.27 1.27)
					(thickness 0.15)
				)
				(justify left bottom)
				(hide yes)
			)
		)
		(property "Description" ""
			(at 76.2 124.46 0)
			(effects
				(font
					(size 1.27 1.27)
				)
				(hide yes)
			)
		)
		(property "MPN" ""
			(at 86.995 135.89 0)
			(effects
				(font
					(size 1.27 1.27)
					(thickness 0.15)
				)
				(justify left bottom)
				(hide yes)
			)
		)
		(property "Manufacturer" ""
			(at 86.995 130.81 0)
			(effects
				(font
					(size 1.27 1.27)
					(thickness 0.15)
				)
				(justify left bottom)
				(hide yes)
			)
		)
		(property "Author" "Antmicro"
			(at 86.995 133.35 0)
			(effects
				(font
					(size 1.27 1.27)
					(thickness 0.15)
				)
				(justify left bottom)
				(hide yes)
			)
		)
		(property "License" "Apache-2.0"
			(at 86.995 135.89 0)
			(effects
				(font
					(size 1.27 1.27)
					(thickness 0.15)
				)
				(justify left bottom)
				(hide yes)
			)
		)
		(property "Public" "False"
			(at 86.36 138.43 0)
			(effects
				(font
					(size 1.27 1.27)
				)
				(justify left bottom)
				(hide yes)
			)
		)
		(pin "1"
		)
		(instances
			(project "com-express-7-baseboard"
				(path ""
					(reference "TP29")
					(unit 1)
				)
			)
		)
	)
	(symbol
		(lib_id "antmicropower:GND")
		(at 218.44 118.11 0)
		(unit 1)
		(exclude_from_sim no)
		(in_bom yes)
		(on_board yes)
		(dnp no)
		(property "Reference" "#PWR0244"
			(at 227.33 120.65 0)
			(effects
				(font
					(size 1.27 1.27)
					(thickness 0.15)
				)
				(justify left bottom)
				(hide yes)
			)
		)
		(property "Value" "GND"
			(at 218.44 121.92 0)
			(effects
				(font
					(size 1.27 1.27)
					(thickness 0.15)
				)
			)
		)
		(property "Footprint" ""
			(at 227.33 125.73 0)
			(effects
				(font
					(size 1.27 1.27)
					(thickness 0.15)
				)
				(justify left bottom)
				(hide yes)
			)
		)
		(property "Datasheet" ""
			(at 227.33 130.81 0)
			(effects
				(font
					(size 1.27 1.27)
					(thickness 0.15)
				)
				(justify left bottom)
				(hide yes)
			)
		)
		(property "Description" ""
			(at 218.44 118.11 0)
			(effects
				(font
					(size 1.27 1.27)
				)
				(hide yes)
			)
		)
		(property "Author" "Antmicro"
			(at 227.33 125.73 0)
			(effects
				(font
					(size 1.27 1.27)
					(thickness 0.15)
				)
				(justify left bottom)
				(hide yes)
			)
		)
		(property "License" "Apache-2.0"
			(at 227.33 128.27 0)
			(effects
				(font
					(size 1.27 1.27)
					(thickness 0.15)
				)
				(justify left bottom)
				(hide yes)
			)
		)
		(pin "1"
		)
		(instances
			(project "com-express-7-baseboard"
				(path ""
					(reference "#PWR0244")
					(unit 1)
				)
			)
		)
	)
	(symbol
		(lib_id "antmicroLogicGatesandInverters:74AUP2G132")
		(at 294.64 140.97 0)
		(unit 1)
		(exclude_from_sim no)
		(in_bom yes)
		(on_board yes)
		(dnp no)
		(fields_autoplaced yes)
		(property "Reference" "U33"
			(at 303.53 134.62 0)
			(effects
				(font
					(size 1.27 1.27)
					(thickness 0.15)
				)
			)
		)
		(property "Value" "74AUP2G132"
			(at 340.36 151.13 0)
			(effects
				(font
					(size 1.27 1.27)
					(thickness 0.15)
				)
				(justify left bottom)
				(hide yes)
			)
		)
		(property "Footprint" "antmicro-footprints:VSSOP-8_2.3x2mm_P0.5mm"
			(at 340.36 153.67 0)
			(effects
				(font
					(size 1.27 1.27)
					(thickness 0.15)
				)
				(justify left bottom)
				(hide yes)
			)
		)
		(property "Datasheet" "https://assets.nexperia.com/documents/data-sheet/74AUP2G132.pdf"
			(at 340.36 156.21 0)
			(effects
				(font
					(size 1.27 1.27)
					(thickness 0.15)
				)
				(justify left bottom)
				(hide yes)
			)
		)
		(property "Description" ""
			(at 294.64 140.97 0)
			(effects
				(font
					(size 1.27 1.27)
				)
				(hide yes)
			)
		)
		(property "Manufacturer" "Nexperia"
			(at 340.36 158.75 0)
			(effects
				(font
					(size 1.27 1.27)
					(thickness 0.15)
				)
				(justify left bottom)
				(hide yes)
			)
		)
		(property "MPN" "74AUP2G132"
			(at 303.53 137.16 0)
			(effects
				(font
					(size 1.27 1.27)
					(thickness 0.15)
				)
			)
		)
		(property "Author" "Antmicro"
			(at 340.36 161.29 0)
			(effects
				(font
					(size 1.27 1.27)
					(thickness 0.15)
				)
				(justify left bottom)
				(hide yes)
			)
		)
		(property "License" "Apache-2.0"
			(at 340.36 163.83 0)
			(effects
				(font
					(size 1.27 1.27)
					(thickness 0.15)
				)
				(justify left bottom)
				(hide yes)
			)
		)
		(pin "4"
		)
		(pin "2"
		)
		(pin "3"
		)
		(pin "1"
		)
		(pin "5"
		)
		(pin "8"
		)
		(pin "6"
		)
		(pin "7"
		)
		(instances
			(project "com-express-7-baseboard"
				(path ""
					(reference "U33")
					(unit 1)
				)
			)
		)
	)
	(symbol
		(lib_id "antmicroResistors0402:R_1k_0402")
		(at 250.19 223.52 90)
		(unit 1)
		(exclude_from_sim no)
		(in_bom yes)
		(on_board yes)
		(dnp no)
		(property "Reference" "R171"
			(at 251.46 220.98 90)
			(effects
				(font
					(size 1.27 1.27)
					(thickness 0.15)
				)
				(justify right)
			)
		)
		(property "Value" "R_1k_0402"
			(at 262.89 203.2 0)
			(effects
				(font
					(size 1.27 1.27)
					(thickness 0.15)
				)
				(justify left bottom)
				(hide yes)
			)
		)
		(property "Footprint" "antmicro-footprints:R_0402_1005Metric"
			(at 265.43 203.2 0)
			(effects
				(font
					(size 1.27 1.27)
					(thickness 0.15)
				)
				(justify left bottom)
				(hide yes)
			)
		)
		(property "Datasheet" "https://www.bourns.com/docs/product-datasheets/cr.pdf"
			(at 267.97 203.2 0)
			(effects
				(font
					(size 1.27 1.27)
					(thickness 0.15)
				)
				(justify left bottom)
				(hide yes)
			)
		)
		(property "Description" ""
			(at 250.19 223.52 0)
			(effects
				(font
					(size 1.27 1.27)
				)
				(hide yes)
			)
		)
		(property "MPN" "CR0402-FX-1001GLF"
			(at 270.51 203.2 0)
			(effects
				(font
					(size 1.27 1.27)
					(thickness 0.15)
				)
				(justify left bottom)
				(hide yes)
			)
		)
		(property "Manufacturer" "Bourns"
			(at 273.05 203.2 0)
			(effects
				(font
					(size 1.27 1.27)
					(thickness 0.15)
				)
				(justify left bottom)
				(hide yes)
			)
		)
		(property "License" "Apache-2.0"
			(at 275.59 203.2 0)
			(effects
				(font
					(size 1.27 1.27)
					(thickness 0.15)
				)
				(justify left bottom)
				(hide yes)
			)
		)
		(property "Author" "Antmicro"
			(at 278.13 203.2 0)
			(effects
				(font
					(size 1.27 1.27)
					(thickness 0.15)
				)
				(justify left bottom)
				(hide yes)
			)
		)
		(property "Val" "1k"
			(at 251.46 223.52 90)
			(effects
				(font
					(size 1.27 1.27)
					(thickness 0.15)
				)
				(justify right)
			)
		)
		(property "Tolerance" "1%"
			(at 260.35 203.2 0)
			(effects
				(font
					(size 1.27 1.27)
				)
				(justify left bottom)
				(hide yes)
			)
		)
		(property "Public" "False"
			(at 280.67 203.2 0)
			(effects
				(font
					(size 1.27 1.27)
				)
				(justify left bottom)
				(hide yes)
			)
		)
		(pin "2"
		)
		(pin "1"
		)
		(instances
			(project "com-express-7-baseboard"
				(path ""
					(reference "R171")
					(unit 1)
				)
			)
		)
	)
	(symbol
		(lib_id "antmicroResistors0402:R_1k_0402")
		(at 356.87 200.66 90)
		(unit 1)
		(exclude_from_sim no)
		(in_bom yes)
		(on_board yes)
		(dnp no)
		(property "Reference" "R181"
			(at 358.14 196.85 90)
			(effects
				(font
					(size 1.27 1.27)
					(thickness 0.15)
				)
				(justify right)
			)
		)
		(property "Value" "R_1k_0402"
			(at 369.57 180.34 0)
			(effects
				(font
					(size 1.27 1.27)
					(thickness 0.15)
				)
				(justify left bottom)
				(hide yes)
			)
		)
		(property "Footprint" "antmicro-footprints:R_0402_1005Metric"
			(at 372.11 180.34 0)
			(effects
				(font
					(size 1.27 1.27)
					(thickness 0.15)
				)
				(justify left bottom)
				(hide yes)
			)
		)
		(property "Datasheet" "https://www.bourns.com/docs/product-datasheets/cr.pdf"
			(at 374.65 180.34 0)
			(effects
				(font
					(size 1.27 1.27)
					(thickness 0.15)
				)
				(justify left bottom)
				(hide yes)
			)
		)
		(property "Description" ""
			(at 356.87 200.66 0)
			(effects
				(font
					(size 1.27 1.27)
				)
				(hide yes)
			)
		)
		(property "MPN" "CR0402-FX-1001GLF"
			(at 377.19 180.34 0)
			(effects
				(font
					(size 1.27 1.27)
					(thickness 0.15)
				)
				(justify left bottom)
				(hide yes)
			)
		)
		(property "Manufacturer" "Bourns"
			(at 379.73 180.34 0)
			(effects
				(font
					(size 1.27 1.27)
					(thickness 0.15)
				)
				(justify left bottom)
				(hide yes)
			)
		)
		(property "License" "Apache-2.0"
			(at 382.27 180.34 0)
			(effects
				(font
					(size 1.27 1.27)
					(thickness 0.15)
				)
				(justify left bottom)
				(hide yes)
			)
		)
		(property "Author" "Antmicro"
			(at 384.81 180.34 0)
			(effects
				(font
					(size 1.27 1.27)
					(thickness 0.15)
				)
				(justify left bottom)
				(hide yes)
			)
		)
		(property "Val" "1k"
			(at 358.14 199.39 90)
			(effects
				(font
					(size 1.27 1.27)
					(thickness 0.15)
				)
				(justify right)
			)
		)
		(property "Tolerance" "1%"
			(at 367.03 180.34 0)
			(effects
				(font
					(size 1.27 1.27)
				)
				(justify left bottom)
				(hide yes)
			)
		)
		(property "Public" "False"
			(at 387.35 180.34 0)
			(effects
				(font
					(size 1.27 1.27)
				)
				(justify left bottom)
				(hide yes)
			)
		)
		(pin "2"
		)
		(pin "1"
		)
		(instances
			(project "com-express-7-baseboard"
				(path ""
					(reference "R181")
					(unit 1)
				)
			)
		)
	)
	(symbol
		(lib_id "antmicroResistors0402:R_5k1_0402")
		(at 91.44 190.5 90)
		(unit 1)
		(exclude_from_sim no)
		(in_bom yes)
		(on_board yes)
		(dnp no)
		(property "Reference" "R161"
			(at 92.71 186.69 90)
			(effects
				(font
					(size 1.27 1.27)
					(thickness 0.15)
				)
				(justify right)
			)
		)
		(property "Value" "R_5k1_0402"
			(at 104.14 170.18 0)
			(effects
				(font
					(size 1.27 1.27)
					(thickness 0.15)
				)
				(justify left bottom)
				(hide yes)
			)
		)
		(property "Footprint" "antmicro-footprints:R_0402_1005Metric"
			(at 106.68 170.18 0)
			(effects
				(font
					(size 1.27 1.27)
					(thickness 0.15)
				)
				(justify left bottom)
				(hide yes)
			)
		)
		(property "Datasheet" "https://www.bourns.com/docs/product-datasheets/cr.pdf"
			(at 109.22 170.18 0)
			(effects
				(font
					(size 1.27 1.27)
					(thickness 0.15)
				)
				(justify left bottom)
				(hide yes)
			)
		)
		(property "Description" ""
			(at 91.44 190.5 0)
			(effects
				(font
					(size 1.27 1.27)
				)
				(hide yes)
			)
		)
		(property "MPN" "CR0402-FX-5101GLF"
			(at 111.76 170.18 0)
			(effects
				(font
					(size 1.27 1.27)
					(thickness 0.15)
				)
				(justify left bottom)
				(hide yes)
			)
		)
		(property "Manufacturer" "Bourns"
			(at 114.3 170.18 0)
			(effects
				(font
					(size 1.27 1.27)
					(thickness 0.15)
				)
				(justify left bottom)
				(hide yes)
			)
		)
		(property "License" "Apache-2.0"
			(at 116.84 170.18 0)
			(effects
				(font
					(size 1.27 1.27)
					(thickness 0.15)
				)
				(justify left bottom)
				(hide yes)
			)
		)
		(property "Author" "Antmicro"
			(at 119.38 170.18 0)
			(effects
				(font
					(size 1.27 1.27)
					(thickness 0.15)
				)
				(justify left bottom)
				(hide yes)
			)
		)
		(property "Val" "5k1"
			(at 92.71 189.23 90)
			(effects
				(font
					(size 1.27 1.27)
					(thickness 0.15)
				)
				(justify right)
			)
		)
		(property "Tolerance" "1%"
			(at 101.6 170.18 0)
			(effects
				(font
					(size 1.27 1.27)
				)
				(justify left bottom)
				(hide yes)
			)
		)
		(property "Public" "False"
			(at 121.92 170.18 0)
			(effects
				(font
					(size 1.27 1.27)
				)
				(justify left bottom)
				(hide yes)
			)
		)
		(pin "1"
		)
		(pin "2"
		)
		(instances
			(project "com-express-7-baseboard"
				(path ""
					(reference "R161")
					(unit 1)
				)
			)
		)
	)
	(symbol
		(lib_id "antmicroTransistorsFETsMOSFETsSingle:BSS138-7-F")
		(at 256.54 102.87 0)
		(unit 1)
		(exclude_from_sim no)
		(in_bom yes)
		(on_board yes)
		(dnp no)
		(property "Reference" "Q11"
			(at 266.7 100.33 0)
			(effects
				(font
					(size 1.27 1.27)
					(thickness 0.15)
				)
				(justify left)
			)
		)
		(property "Value" "BSS138-7-F"
			(at 265.43 104.14 0)
			(effects
				(font
					(size 1.27 1.27)
					(thickness 0.15)
				)
				(justify left)
				(hide yes)
			)
		)
		(property "Footprint" "antmicro-footprints:SOT-23-3"
			(at 279.4 110.49 0)
			(effects
				(font
					(size 1.27 1.27)
					(thickness 0.15)
				)
				(justify left bottom)
				(hide yes)
			)
		)
		(property "Datasheet" "https://www.diodes.com/assets/Datasheets/ds30144.pdf"
			(at 279.4 113.03 0)
			(effects
				(font
					(size 1.27 1.27)
					(thickness 0.15)
				)
				(justify left bottom)
				(hide yes)
			)
		)
		(property "Description" ""
			(at 256.54 102.87 0)
			(effects
				(font
					(size 1.27 1.27)
				)
				(hide yes)
			)
		)
		(property "MPN" "BSS138-7-F"
			(at 266.7 102.87 0)
			(effects
				(font
					(size 1.27 1.27)
					(thickness 0.15)
				)
				(justify left bottom)
			)
		)
		(property "Manufacturer" "Diodes Incorporated"
			(at 279.4 118.11 0)
			(effects
				(font
					(size 1.27 1.27)
					(thickness 0.15)
				)
				(justify left bottom)
				(hide yes)
			)
		)
		(property "Author" "Antmicro"
			(at 279.4 120.65 0)
			(effects
				(font
					(size 1.27 1.27)
					(thickness 0.15)
				)
				(justify left bottom)
				(hide yes)
			)
		)
		(property "License" "Apache-2.0"
			(at 279.4 123.19 0)
			(effects
				(font
					(size 1.27 1.27)
					(thickness 0.15)
				)
				(justify left bottom)
				(hide yes)
			)
		)
		(pin "1"
		)
		(pin "2"
		)
		(pin "3"
		)
		(instances
			(project "com-express-7-baseboard"
				(path ""
					(reference "Q11")
					(unit 1)
				)
			)
		)
	)
	(symbol
		(lib_id "antmicropower:GND")
		(at 360.68 246.38 0)
		(unit 1)
		(exclude_from_sim no)
		(in_bom yes)
		(on_board yes)
		(dnp no)
		(property "Reference" "#PWR0268"
			(at 369.57 248.92 0)
			(effects
				(font
					(size 1.27 1.27)
					(thickness 0.15)
				)
				(justify left bottom)
				(hide yes)
			)
		)
		(property "Value" "GND"
			(at 360.68 250.19 0)
			(effects
				(font
					(size 1.27 1.27)
					(thickness 0.15)
				)
			)
		)
		(property "Footprint" ""
			(at 369.57 254 0)
			(effects
				(font
					(size 1.27 1.27)
					(thickness 0.15)
				)
				(justify left bottom)
				(hide yes)
			)
		)
		(property "Datasheet" ""
			(at 369.57 259.08 0)
			(effects
				(font
					(size 1.27 1.27)
					(thickness 0.15)
				)
				(justify left bottom)
				(hide yes)
			)
		)
		(property "Description" ""
			(at 360.68 246.38 0)
			(effects
				(font
					(size 1.27 1.27)
				)
				(hide yes)
			)
		)
		(property "Author" "Antmicro"
			(at 369.57 254 0)
			(effects
				(font
					(size 1.27 1.27)
					(thickness 0.15)
				)
				(justify left bottom)
				(hide yes)
			)
		)
		(property "License" "Apache-2.0"
			(at 369.57 256.54 0)
			(effects
				(font
					(size 1.27 1.27)
					(thickness 0.15)
				)
				(justify left bottom)
				(hide yes)
			)
		)
		(pin "1"
		)
		(instances
			(project "com-express-7-baseboard"
				(path ""
					(reference "#PWR0268")
					(unit 1)
				)
			)
		)
	)
	(symbol
		(lib_id "antmicropower:+3V3_AON")
		(at 302.26 50.8 0)
		(unit 1)
		(exclude_from_sim no)
		(in_bom yes)
		(on_board yes)
		(dnp no)
		(property "Reference" "#PWR0260"
			(at 302.26 54.61 0)
			(effects
				(font
					(size 1.27 1.27)
				)
				(hide yes)
			)
		)
		(property "Value" "+3V3_AON"
			(at 302.26 46.99 0)
			(effects
				(font
					(size 1.27 1.27)
				)
			)
		)
		(property "Footprint" ""
			(at 302.26 50.8 0)
			(effects
				(font
					(size 1.27 1.27)
				)
				(hide yes)
			)
		)
		(property "Datasheet" ""
			(at 302.26 50.8 0)
			(effects
				(font
					(size 1.27 1.27)
				)
				(hide yes)
			)
		)
		(property "Description" ""
			(at 302.26 50.8 0)
			(effects
				(font
					(size 1.27 1.27)
				)
				(hide yes)
			)
		)
		(pin "1"
		)
		(instances
			(project "com-express-7-baseboard"
				(path ""
					(reference "#PWR0260")
					(unit 1)
				)
			)
		)
	)
	(symbol
		(lib_id "antmicroTestPoints:TP_0.75mm_SMD")
		(at 76.2 114.3 0)
		(unit 1)
		(exclude_from_sim no)
		(in_bom no)
		(on_board yes)
		(dnp no)
		(fields_autoplaced yes)
		(property "Reference" "TP25"
			(at 81.28 114.3 0)
			(effects
				(font
					(size 1.27 1.27)
					(thickness 0.15)
				)
				(justify left)
			)
		)
		(property "Value" "TP_0.75mm_SMD"
			(at 86.995 118.11 0)
			(effects
				(font
					(size 1.27 1.27)
					(thickness 0.15)
				)
				(justify left bottom)
				(hide yes)
			)
		)
		(property "Footprint" "antmicro-footprints:TP_SMD_0.75mm"
			(at 86.995 120.65 0)
			(effects
				(font
					(size 1.27 1.27)
					(thickness 0.15)
				)
				(justify left bottom)
				(hide yes)
			)
		)
		(property "Datasheet" ""
			(at 93.98 127 0)
			(effects
				(font
					(size 1.27 1.27)
					(thickness 0.15)
				)
				(justify left bottom)
				(hide yes)
			)
		)
		(property "Description" ""
			(at 76.2 114.3 0)
			(effects
				(font
					(size 1.27 1.27)
				)
				(hide yes)
			)
		)
		(property "MPN" ""
			(at 86.995 125.73 0)
			(effects
				(font
					(size 1.27 1.27)
					(thickness 0.15)
				)
				(justify left bottom)
				(hide yes)
			)
		)
		(property "Manufacturer" ""
			(at 86.995 120.65 0)
			(effects
				(font
					(size 1.27 1.27)
					(thickness 0.15)
				)
				(justify left bottom)
				(hide yes)
			)
		)
		(property "Author" "Antmicro"
			(at 86.995 123.19 0)
			(effects
				(font
					(size 1.27 1.27)
					(thickness 0.15)
				)
				(justify left bottom)
				(hide yes)
			)
		)
		(property "License" "Apache-2.0"
			(at 86.995 125.73 0)
			(effects
				(font
					(size 1.27 1.27)
					(thickness 0.15)
				)
				(justify left bottom)
				(hide yes)
			)
		)
		(property "Public" "False"
			(at 86.36 128.27 0)
			(effects
				(font
					(size 1.27 1.27)
				)
				(justify left bottom)
				(hide yes)
			)
		)
		(pin "1"
		)
		(instances
			(project "com-express-7-baseboard"
				(path ""
					(reference "TP25")
					(unit 1)
				)
			)
		)
	)
	(symbol
		(lib_id "antmicroShuntsJumpers:Jumper_1x2_P2.54mm")
		(at 271.78 85.09 0)
		(unit 1)
		(exclude_from_sim no)
		(in_bom yes)
		(on_board yes)
		(dnp no)
		(property "Reference" "JP3"
			(at 271.145 83.82 0)
			(effects
				(font
					(size 1.27 1.27)
				)
				(justify left)
			)
		)
		(property "Value" "Jumper_1x2_P2.54mm"
			(at 271.145 91.44 0)
			(effects
				(font
					(size 1.27 1.27)
				)
				(justify left)
			)
		)
		(property "Footprint" "antmicro-footprints:Jumper_1x2_P2.54mm"
			(at 271.78 87.63 0)
			(effects
				(font
					(size 1.27 1.27)
				)
				(hide yes)
			)
		)
		(property "Datasheet" "https://www.tme.eu/en/details/jumper-w/pin-headers/ninigi/"
			(at 271.78 85.09 0)
			(effects
				(font
					(size 1.27 1.27)
				)
				(hide yes)
			)
		)
		(property "Description" ""
			(at 271.78 85.09 0)
			(effects
				(font
					(size 1.27 1.27)
				)
				(hide yes)
			)
		)
		(property "MPN" "JUMPER-W"
			(at 271.78 90.17 0)
			(effects
				(font
					(size 1.27 1.27)
				)
				(hide yes)
			)
		)
		(property "Manufacturer" "Ninigi"
			(at 271.78 92.075 0)
			(effects
				(font
					(size 1.27 1.27)
				)
				(hide yes)
			)
		)
		(property "License" "Apache-2.0"
			(at 271.78 95.885 0)
			(effects
				(font
					(size 1.27 1.27)
				)
				(hide yes)
			)
		)
		(property "Author" "Antmicro"
			(at 271.78 93.98 0)
			(effects
				(font
					(size 1.27 1.27)
				)
				(hide yes)
			)
		)
		(instances
			(project "com-express-7-baseboard"
				(path ""
					(reference "JP3")
					(unit 1)
				)
			)
		)
	)
	(symbol
		(lib_id "antmicroDiodesRectifiersSingle:BAT54C")
		(at 228.6 68.58 90)
		(unit 1)
		(exclude_from_sim no)
		(in_bom yes)
		(on_board yes)
		(dnp no)
		(fields_autoplaced yes)
		(property "Reference" "D35"
			(at 237.49 60.96 90)
			(effects
				(font
					(size 1.27 1.27)
					(thickness 0.15)
				)
				(justify right)
			)
		)
		(property "Value" "BAT54C"
			(at 237.49 45.72 0)
			(effects
				(font
					(size 1.27 1.27)
					(thickness 0.15)
				)
				(justify left bottom)
				(hide yes)
			)
		)
		(property "Footprint" "antmicro-footprints:SOT-23-3"
			(at 240.03 45.72 0)
			(effects
				(font
					(size 1.27 1.27)
					(thickness 0.15)
				)
				(justify left bottom)
				(hide yes)
			)
		)
		(property "Datasheet" "https://diotec.com/request/datasheet/bat54.pdf"
			(at 242.57 45.72 0)
			(effects
				(font
					(size 1.27 1.27)
					(thickness 0.15)
				)
				(justify left bottom)
				(hide yes)
			)
		)
		(property "Description" ""
			(at 228.6 68.58 0)
			(effects
				(font
					(size 1.27 1.27)
				)
				(hide yes)
			)
		)
		(property "MPN" "BAT54C"
			(at 237.49 63.5 90)
			(effects
				(font
					(size 1.27 1.27)
					(thickness 0.15)
				)
				(justify right)
			)
		)
		(property "Manufacturer" "Diotec Semiconductor"
			(at 245.11 45.72 0)
			(effects
				(font
					(size 1.27 1.27)
					(thickness 0.15)
				)
				(justify left bottom)
				(hide yes)
			)
		)
		(property "Author" "Antmicro"
			(at 247.65 45.72 0)
			(effects
				(font
					(size 1.27 1.27)
					(thickness 0.15)
				)
				(justify left bottom)
				(hide yes)
			)
		)
		(property "License" "Apache-2.0"
			(at 250.19 45.72 0)
			(effects
				(font
					(size 1.27 1.27)
					(thickness 0.15)
				)
				(justify left bottom)
				(hide yes)
			)
		)
		(pin "1"
		)
		(pin "3"
		)
		(pin "2"
		)
		(instances
			(project "com-express-7-baseboard"
				(path ""
					(reference "D35")
					(unit 1)
				)
			)
		)
	)
	(symbol
		(lib_id "antmicroTestPoints:TP_0.75mm_SMD")
		(at 76.2 121.92 0)
		(unit 1)
		(exclude_from_sim no)
		(in_bom no)
		(on_board yes)
		(dnp no)
		(fields_autoplaced yes)
		(property "Reference" "TP28"
			(at 81.28 121.92 0)
			(effects
				(font
					(size 1.27 1.27)
					(thickness 0.15)
				)
				(justify left)
			)
		)
		(property "Value" "TP_0.75mm_SMD"
			(at 86.995 125.73 0)
			(effects
				(font
					(size 1.27 1.27)
					(thickness 0.15)
				)
				(justify left bottom)
				(hide yes)
			)
		)
		(property "Footprint" "antmicro-footprints:TP_SMD_0.75mm"
			(at 86.995 128.27 0)
			(effects
				(font
					(size 1.27 1.27)
					(thickness 0.15)
				)
				(justify left bottom)
				(hide yes)
			)
		)
		(property "Datasheet" ""
			(at 93.98 134.62 0)
			(effects
				(font
					(size 1.27 1.27)
					(thickness 0.15)
				)
				(justify left bottom)
				(hide yes)
			)
		)
		(property "Description" ""
			(at 76.2 121.92 0)
			(effects
				(font
					(size 1.27 1.27)
				)
				(hide yes)
			)
		)
		(property "MPN" ""
			(at 86.995 133.35 0)
			(effects
				(font
					(size 1.27 1.27)
					(thickness 0.15)
				)
				(justify left bottom)
				(hide yes)
			)
		)
		(property "Manufacturer" ""
			(at 86.995 128.27 0)
			(effects
				(font
					(size 1.27 1.27)
					(thickness 0.15)
				)
				(justify left bottom)
				(hide yes)
			)
		)
		(property "Author" "Antmicro"
			(at 86.995 130.81 0)
			(effects
				(font
					(size 1.27 1.27)
					(thickness 0.15)
				)
				(justify left bottom)
				(hide yes)
			)
		)
		(property "License" "Apache-2.0"
			(at 86.995 133.35 0)
			(effects
				(font
					(size 1.27 1.27)
					(thickness 0.15)
				)
				(justify left bottom)
				(hide yes)
			)
		)
		(property "Public" "False"
			(at 86.36 135.89 0)
			(effects
				(font
					(size 1.27 1.27)
				)
				(justify left bottom)
				(hide yes)
			)
		)
		(pin "1"
		)
		(instances
			(project "com-express-7-baseboard"
				(path ""
					(reference "TP28")
					(unit 1)
				)
			)
		)
	)
	(symbol
		(lib_id "antmicropower:GND")
		(at 93.98 46.99 0)
		(unit 1)
		(exclude_from_sim no)
		(in_bom yes)
		(on_board yes)
		(dnp no)
		(property "Reference" "#PWR0228"
			(at 102.87 49.53 0)
			(effects
				(font
					(size 1.27 1.27)
					(thickness 0.15)
				)
				(justify left bottom)
				(hide yes)
			)
		)
		(property "Value" "GND"
			(at 93.98 50.8 0)
			(effects
				(font
					(size 1.27 1.27)
					(thickness 0.15)
				)
			)
		)
		(property "Footprint" ""
			(at 102.87 54.61 0)
			(effects
				(font
					(size 1.27 1.27)
					(thickness 0.15)
				)
				(justify left bottom)
				(hide yes)
			)
		)
		(property "Datasheet" ""
			(at 102.87 59.69 0)
			(effects
				(font
					(size 1.27 1.27)
					(thickness 0.15)
				)
				(justify left bottom)
				(hide yes)
			)
		)
		(property "Description" ""
			(at 93.98 46.99 0)
			(effects
				(font
					(size 1.27 1.27)
				)
				(hide yes)
			)
		)
		(property "Author" "Antmicro"
			(at 102.87 54.61 0)
			(effects
				(font
					(size 1.27 1.27)
					(thickness 0.15)
				)
				(justify left bottom)
				(hide yes)
			)
		)
		(property "License" "Apache-2.0"
			(at 102.87 57.15 0)
			(effects
				(font
					(size 1.27 1.27)
					(thickness 0.15)
				)
				(justify left bottom)
				(hide yes)
			)
		)
		(pin "1"
		)
		(instances
			(project "com-express-7-baseboard"
				(path ""
					(reference "#PWR0228")
					(unit 1)
				)
			)
		)
	)
	(symbol
		(lib_id "antmicroGenericPinHeaders:PinHeader_1x3_P2.54mm_Drill1.1mm")
		(at 254 85.09 0)
		(mirror y)
		(unit 1)
		(exclude_from_sim no)
		(in_bom yes)
		(on_board yes)
		(dnp no)
		(fields_autoplaced yes)
		(property "Reference" "J7"
			(at 247.65 86.3599 0)
			(effects
				(font
					(size 1.27 1.27)
					(thickness 0.15)
				)
				(justify left)
			)
		)
		(property "Value" "PinHeader_1x3_P2.54mm_Drill1.1mm"
			(at 233.68 95.25 0)
			(effects
				(font
					(size 1.27 1.27)
					(thickness 0.15)
				)
				(justify left bottom)
				(hide yes)
			)
		)
		(property "Footprint" "antmicro-footprints:PinHeader_1x3_P2.54mm_Drill1.1mm"
			(at 233.68 97.79 0)
			(effects
				(font
					(size 1.27 1.27)
					(thickness 0.15)
				)
				(justify left bottom)
				(hide yes)
			)
		)
		(property "Datasheet" "https://katalog.we-online.de/em/datasheet/6130xx11121.pdf"
			(at 233.68 100.33 0)
			(effects
				(font
					(size 1.27 1.27)
					(thickness 0.15)
				)
				(justify left bottom)
				(hide yes)
			)
		)
		(property "Description" ""
			(at 254 85.09 0)
			(effects
				(font
					(size 1.27 1.27)
				)
				(hide yes)
			)
		)
		(property "MPN" "61300311121"
			(at 247.65 88.8999 0)
			(effects
				(font
					(size 1.27 1.27)
					(thickness 0.15)
				)
				(justify left)
			)
		)
		(property "Manufacturer" "Würth Elektronik"
			(at 233.68 102.87 0)
			(effects
				(font
					(size 1.27 1.27)
					(thickness 0.15)
				)
				(justify left bottom)
				(hide yes)
			)
		)
		(property "Author" "Antmicro"
			(at 233.68 107.95 0)
			(effects
				(font
					(size 1.27 1.27)
					(thickness 0.15)
				)
				(justify left bottom)
				(hide yes)
			)
		)
		(property "License" "Apache-2.0"
			(at 233.68 110.49 0)
			(effects
				(font
					(size 1.27 1.27)
					(thickness 0.15)
				)
				(justify left bottom)
				(hide yes)
			)
		)
		(pin "3"
		)
		(pin "2"
		)
		(pin "1"
		)
		(instances
			(project "com-express-7-baseboard"
				(path ""
					(reference "J7")
					(unit 1)
				)
			)
		)
	)
	(symbol
		(lib_id "antmicropower:+3V3_AON")
		(at 231.14 50.8 0)
		(unit 1)
		(exclude_from_sim no)
		(in_bom yes)
		(on_board yes)
		(dnp no)
		(property "Reference" "#PWR0472"
			(at 231.14 54.61 0)
			(effects
				(font
					(size 1.27 1.27)
				)
				(hide yes)
			)
		)
		(property "Value" "+3V3_AON"
			(at 231.14 46.99 0)
			(effects
				(font
					(size 1.27 1.27)
				)
			)
		)
		(property "Footprint" ""
			(at 231.14 50.8 0)
			(effects
				(font
					(size 1.27 1.27)
				)
				(hide yes)
			)
		)
		(property "Datasheet" ""
			(at 231.14 50.8 0)
			(effects
				(font
					(size 1.27 1.27)
				)
				(hide yes)
			)
		)
		(property "Description" ""
			(at 231.14 50.8 0)
			(effects
				(font
					(size 1.27 1.27)
				)
				(hide yes)
			)
		)
		(pin "1"
		)
		(instances
			(project "com-express-7-baseboard"
				(path ""
					(reference "#PWR0472")
					(unit 1)
				)
			)
		)
	)
	(symbol
		(lib_id "antmicroTestPoints:TP_0.75mm_SMD")
		(at 76.2 109.22 0)
		(unit 1)
		(exclude_from_sim no)
		(in_bom no)
		(on_board yes)
		(dnp no)
		(fields_autoplaced yes)
		(property "Reference" "TP23"
			(at 81.28 109.22 0)
			(effects
				(font
					(size 1.27 1.27)
					(thickness 0.15)
				)
				(justify left)
			)
		)
		(property "Value" "TP_0.75mm_SMD"
			(at 86.995 113.03 0)
			(effects
				(font
					(size 1.27 1.27)
					(thickness 0.15)
				)
				(justify left bottom)
				(hide yes)
			)
		)
		(property "Footprint" "antmicro-footprints:TP_SMD_0.75mm"
			(at 86.995 115.57 0)
			(effects
				(font
					(size 1.27 1.27)
					(thickness 0.15)
				)
				(justify left bottom)
				(hide yes)
			)
		)
		(property "Datasheet" ""
			(at 93.98 121.92 0)
			(effects
				(font
					(size 1.27 1.27)
					(thickness 0.15)
				)
				(justify left bottom)
				(hide yes)
			)
		)
		(property "Description" ""
			(at 76.2 109.22 0)
			(effects
				(font
					(size 1.27 1.27)
				)
				(hide yes)
			)
		)
		(property "MPN" ""
			(at 86.995 120.65 0)
			(effects
				(font
					(size 1.27 1.27)
					(thickness 0.15)
				)
				(justify left bottom)
				(hide yes)
			)
		)
		(property "Manufacturer" ""
			(at 86.995 115.57 0)
			(effects
				(font
					(size 1.27 1.27)
					(thickness 0.15)
				)
				(justify left bottom)
				(hide yes)
			)
		)
		(property "Author" "Antmicro"
			(at 86.995 118.11 0)
			(effects
				(font
					(size 1.27 1.27)
					(thickness 0.15)
				)
				(justify left bottom)
				(hide yes)
			)
		)
		(property "License" "Apache-2.0"
			(at 86.995 120.65 0)
			(effects
				(font
					(size 1.27 1.27)
					(thickness 0.15)
				)
				(justify left bottom)
				(hide yes)
			)
		)
		(property "Public" "False"
			(at 86.36 123.19 0)
			(effects
				(font
					(size 1.27 1.27)
				)
				(justify left bottom)
				(hide yes)
			)
		)
		(pin "1"
		)
		(instances
			(project "com-express-7-baseboard"
				(path ""
					(reference "TP23")
					(unit 1)
				)
			)
		)
	)
	(symbol
		(lib_id "antmicroTestPoints:TP_0.75mm_SMD")
		(at 231.14 105.41 180)
		(unit 1)
		(exclude_from_sim no)
		(in_bom no)
		(on_board yes)
		(dnp no)
		(property "Reference" "TP43"
			(at 224.79 105.41 0)
			(effects
				(font
					(size 1.27 1.27)
					(thickness 0.15)
				)
			)
		)
		(property "Value" "TP_0.75mm_SMD"
			(at 220.345 101.6 0)
			(effects
				(font
					(size 1.27 1.27)
					(thickness 0.15)
				)
				(justify left bottom)
				(hide yes)
			)
		)
		(property "Footprint" "antmicro-footprints:TP_SMD_0.75mm"
			(at 220.345 99.06 0)
			(effects
				(font
					(size 1.27 1.27)
					(thickness 0.15)
				)
				(justify left bottom)
				(hide yes)
			)
		)
		(property "Datasheet" ""
			(at 213.36 92.71 0)
			(effects
				(font
					(size 1.27 1.27)
					(thickness 0.15)
				)
				(justify left bottom)
				(hide yes)
			)
		)
		(property "Description" ""
			(at 231.14 105.41 0)
			(effects
				(font
					(size 1.27 1.27)
				)
				(hide yes)
			)
		)
		(property "MPN" ""
			(at 220.345 93.98 0)
			(effects
				(font
					(size 1.27 1.27)
					(thickness 0.15)
				)
				(justify left bottom)
				(hide yes)
			)
		)
		(property "Manufacturer" ""
			(at 220.345 99.06 0)
			(effects
				(font
					(size 1.27 1.27)
					(thickness 0.15)
				)
				(justify left bottom)
				(hide yes)
			)
		)
		(property "Author" "Antmicro"
			(at 220.345 96.52 0)
			(effects
				(font
					(size 1.27 1.27)
					(thickness 0.15)
				)
				(justify left bottom)
				(hide yes)
			)
		)
		(property "License" "Apache-2.0"
			(at 220.345 93.98 0)
			(effects
				(font
					(size 1.27 1.27)
					(thickness 0.15)
				)
				(justify left bottom)
				(hide yes)
			)
		)
		(property "Public" "False"
			(at 220.98 91.44 0)
			(effects
				(font
					(size 1.27 1.27)
				)
				(justify left bottom)
				(hide yes)
			)
		)
		(pin "1"
		)
		(instances
			(project "com-express-7-baseboard"
				(path ""
					(reference "TP43")
					(unit 1)
				)
			)
		)
	)
	(symbol
		(lib_id "antmicropower:+3V3_AON")
		(at 264.16 41.91 0)
		(unit 1)
		(exclude_from_sim no)
		(in_bom yes)
		(on_board yes)
		(dnp no)
		(property "Reference" "#PWR0257"
			(at 264.16 45.72 0)
			(effects
				(font
					(size 1.27 1.27)
				)
				(hide yes)
			)
		)
		(property "Value" "+3V3_AON"
			(at 264.16 38.1 0)
			(effects
				(font
					(size 1.27 1.27)
				)
			)
		)
		(property "Footprint" ""
			(at 264.16 41.91 0)
			(effects
				(font
					(size 1.27 1.27)
				)
				(hide yes)
			)
		)
		(property "Datasheet" ""
			(at 264.16 41.91 0)
			(effects
				(font
					(size 1.27 1.27)
				)
				(hide yes)
			)
		)
		(property "Description" ""
			(at 264.16 41.91 0)
			(effects
				(font
					(size 1.27 1.27)
				)
				(hide yes)
			)
		)
		(pin "1"
		)
		(instances
			(project "com-express-7-baseboard"
				(path ""
					(reference "#PWR0257")
					(unit 1)
				)
			)
		)
	)
	(symbol
		(lib_id "antmicroCapacitors0402:C_100n_0402")
		(at 218.44 115.57 90)
		(unit 1)
		(exclude_from_sim no)
		(in_bom yes)
		(on_board yes)
		(dnp no)
		(fields_autoplaced yes)
		(property "Reference" "C97"
			(at 220.98 111.7536 90)
			(effects
				(font
					(size 1.27 1.27)
					(thickness 0.15)
				)
				(justify right)
			)
		)
		(property "Value" "C_100n_0402"
			(at 228.6 95.25 0)
			(effects
				(font
					(size 1.27 1.27)
					(thickness 0.15)
				)
				(justify left bottom)
				(hide yes)
			)
		)
		(property "Footprint" "antmicro-footprints:C_0402_1005Metric"
			(at 231.14 95.25 0)
			(effects
				(font
					(size 1.27 1.27)
					(thickness 0.15)
				)
				(justify left bottom)
				(hide yes)
			)
		)
		(property "Datasheet" "https://www.murata.com/products/productdetail?partno=GRM155R61H104KE14%23"
			(at 233.68 95.25 0)
			(effects
				(font
					(size 1.27 1.27)
					(thickness 0.15)
				)
				(justify left bottom)
				(hide yes)
			)
		)
		(property "Description" ""
			(at 218.44 115.57 0)
			(effects
				(font
					(size 1.27 1.27)
				)
				(hide yes)
			)
		)
		(property "MPN" "GRM155R61H104KE14D"
			(at 236.22 95.25 0)
			(effects
				(font
					(size 1.27 1.27)
					(thickness 0.15)
				)
				(justify left bottom)
				(hide yes)
			)
		)
		(property "Manufacturer" "Murata"
			(at 238.76 95.25 0)
			(effects
				(font
					(size 1.27 1.27)
					(thickness 0.15)
				)
				(justify left bottom)
				(hide yes)
			)
		)
		(property "License" "Apache-2.0"
			(at 241.3 95.25 0)
			(effects
				(font
					(size 1.27 1.27)
					(thickness 0.15)
				)
				(justify left bottom)
				(hide yes)
			)
		)
		(property "Author" "Antmicro"
			(at 243.84 95.25 0)
			(effects
				(font
					(size 1.27 1.27)
					(thickness 0.15)
				)
				(justify left bottom)
				(hide yes)
			)
		)
		(property "Val" "100n"
			(at 220.98 114.2936 90)
			(effects
				(font
					(size 1.27 1.27)
					(thickness 0.15)
				)
				(justify right)
			)
		)
		(property "Voltage" "50V"
			(at 246.38 95.25 0)
			(effects
				(font
					(size 1.27 1.27)
				)
				(justify left bottom)
				(hide yes)
			)
		)
		(property "Dielectric" "X5R"
			(at 248.92 95.25 0)
			(effects
				(font
					(size 1.27 1.27)
				)
				(justify left bottom)
				(hide yes)
			)
		)
		(property "Public" "False"
			(at 251.46 95.25 0)
			(effects
				(font
					(size 1.27 1.27)
				)
				(justify left bottom)
				(hide yes)
			)
		)
		(pin "1"
		)
		(pin "2"
		)
		(instances
			(project "com-express-7-baseboard"
				(path ""
					(reference "C97")
					(unit 1)
				)
			)
		)
	)
	(symbol
		(lib_id "antmicroResistors0402:R_10k_0402")
		(at 264.16 138.43 90)
		(unit 1)
		(exclude_from_sim no)
		(in_bom yes)
		(on_board yes)
		(dnp no)
		(property "Reference" "R169"
			(at 265.43 134.62 90)
			(effects
				(font
					(size 1.27 1.27)
					(thickness 0.15)
				)
				(justify right)
			)
		)
		(property "Value" "R_10k_0402"
			(at 276.86 118.11 0)
			(effects
				(font
					(size 1.27 1.27)
					(thickness 0.15)
				)
				(justify left bottom)
				(hide yes)
			)
		)
		(property "Footprint" "antmicro-footprints:R_0402_1005Metric"
			(at 279.4 118.11 0)
			(effects
				(font
					(size 1.27 1.27)
					(thickness 0.15)
				)
				(justify left bottom)
				(hide yes)
			)
		)
		(property "Datasheet" "https://www.bourns.com/docs/product-datasheets/cr.pdf"
			(at 281.94 118.11 0)
			(effects
				(font
					(size 1.27 1.27)
					(thickness 0.15)
				)
				(justify left bottom)
				(hide yes)
			)
		)
		(property "Description" ""
			(at 264.16 138.43 0)
			(effects
				(font
					(size 1.27 1.27)
				)
				(hide yes)
			)
		)
		(property "MPN" "CR0402-FX-1002GLF"
			(at 284.48 118.11 0)
			(effects
				(font
					(size 1.27 1.27)
					(thickness 0.15)
				)
				(justify left bottom)
				(hide yes)
			)
		)
		(property "Manufacturer" "Bourns"
			(at 287.02 118.11 0)
			(effects
				(font
					(size 1.27 1.27)
					(thickness 0.15)
				)
				(justify left bottom)
				(hide yes)
			)
		)
		(property "License" "Apache-2.0"
			(at 289.56 118.11 0)
			(effects
				(font
					(size 1.27 1.27)
					(thickness 0.15)
				)
				(justify left bottom)
				(hide yes)
			)
		)
		(property "Author" "Antmicro"
			(at 292.1 118.11 0)
			(effects
				(font
					(size 1.27 1.27)
					(thickness 0.15)
				)
				(justify left bottom)
				(hide yes)
			)
		)
		(property "Val" "10k"
			(at 265.43 137.16 90)
			(effects
				(font
					(size 1.27 1.27)
					(thickness 0.15)
				)
				(justify right)
			)
		)
		(property "Tolerance" "1%"
			(at 274.32 118.11 0)
			(effects
				(font
					(size 1.27 1.27)
				)
				(justify left bottom)
				(hide yes)
			)
		)
		(property "Public" "False"
			(at 294.64 118.11 0)
			(effects
				(font
					(size 1.27 1.27)
				)
				(justify left bottom)
				(hide yes)
			)
		)
		(pin "1"
		)
		(pin "2"
		)
		(instances
			(project "com-express-7-baseboard"
				(path ""
					(reference "R169")
					(unit 1)
				)
			)
		)
	)
	(symbol
		(lib_id "antmicropower:GND")
		(at 317.5 78.74 0)
		(unit 1)
		(exclude_from_sim no)
		(in_bom yes)
		(on_board yes)
		(dnp no)
		(property "Reference" "#PWR0450"
			(at 326.39 81.28 0)
			(effects
				(font
					(size 1.27 1.27)
					(thickness 0.15)
				)
				(justify left bottom)
				(hide yes)
			)
		)
		(property "Value" "GND"
			(at 317.5 82.55 0)
			(effects
				(font
					(size 1.27 1.27)
					(thickness 0.15)
				)
			)
		)
		(property "Footprint" ""
			(at 326.39 86.36 0)
			(effects
				(font
					(size 1.27 1.27)
					(thickness 0.15)
				)
				(justify left bottom)
				(hide yes)
			)
		)
		(property "Datasheet" ""
			(at 326.39 91.44 0)
			(effects
				(font
					(size 1.27 1.27)
					(thickness 0.15)
				)
				(justify left bottom)
				(hide yes)
			)
		)
		(property "Description" ""
			(at 317.5 78.74 0)
			(effects
				(font
					(size 1.27 1.27)
				)
				(hide yes)
			)
		)
		(property "Author" "Antmicro"
			(at 326.39 86.36 0)
			(effects
				(font
					(size 1.27 1.27)
					(thickness 0.15)
				)
				(justify left bottom)
				(hide yes)
			)
		)
		(property "License" "Apache-2.0"
			(at 326.39 88.9 0)
			(effects
				(font
					(size 1.27 1.27)
					(thickness 0.15)
				)
				(justify left bottom)
				(hide yes)
			)
		)
		(pin "1"
		)
		(instances
			(project "com-express-7-baseboard"
				(path ""
					(reference "#PWR0450")
					(unit 1)
				)
			)
		)
	)
	(symbol
		(lib_id "antmicroResistors0402:R_1k_0402")
		(at 349.25 200.66 90)
		(unit 1)
		(exclude_from_sim no)
		(in_bom yes)
		(on_board yes)
		(dnp no)
		(property "Reference" "R179"
			(at 350.52 196.85 90)
			(effects
				(font
					(size 1.27 1.27)
					(thickness 0.15)
				)
				(justify right)
			)
		)
		(property "Value" "R_1k_0402"
			(at 361.95 180.34 0)
			(effects
				(font
					(size 1.27 1.27)
					(thickness 0.15)
				)
				(justify left bottom)
				(hide yes)
			)
		)
		(property "Footprint" "antmicro-footprints:R_0402_1005Metric"
			(at 364.49 180.34 0)
			(effects
				(font
					(size 1.27 1.27)
					(thickness 0.15)
				)
				(justify left bottom)
				(hide yes)
			)
		)
		(property "Datasheet" "https://www.bourns.com/docs/product-datasheets/cr.pdf"
			(at 367.03 180.34 0)
			(effects
				(font
					(size 1.27 1.27)
					(thickness 0.15)
				)
				(justify left bottom)
				(hide yes)
			)
		)
		(property "Description" ""
			(at 349.25 200.66 0)
			(effects
				(font
					(size 1.27 1.27)
				)
				(hide yes)
			)
		)
		(property "MPN" "CR0402-FX-1001GLF"
			(at 369.57 180.34 0)
			(effects
				(font
					(size 1.27 1.27)
					(thickness 0.15)
				)
				(justify left bottom)
				(hide yes)
			)
		)
		(property "Manufacturer" "Bourns"
			(at 372.11 180.34 0)
			(effects
				(font
					(size 1.27 1.27)
					(thickness 0.15)
				)
				(justify left bottom)
				(hide yes)
			)
		)
		(property "License" "Apache-2.0"
			(at 374.65 180.34 0)
			(effects
				(font
					(size 1.27 1.27)
					(thickness 0.15)
				)
				(justify left bottom)
				(hide yes)
			)
		)
		(property "Author" "Antmicro"
			(at 377.19 180.34 0)
			(effects
				(font
					(size 1.27 1.27)
					(thickness 0.15)
				)
				(justify left bottom)
				(hide yes)
			)
		)
		(property "Val" "1k"
			(at 350.52 199.39 90)
			(effects
				(font
					(size 1.27 1.27)
					(thickness 0.15)
				)
				(justify right)
			)
		)
		(property "Tolerance" "1%"
			(at 359.41 180.34 0)
			(effects
				(font
					(size 1.27 1.27)
				)
				(justify left bottom)
				(hide yes)
			)
		)
		(property "Public" "False"
			(at 379.73 180.34 0)
			(effects
				(font
					(size 1.27 1.27)
				)
				(justify left bottom)
				(hide yes)
			)
		)
		(pin "2"
		)
		(pin "1"
		)
		(instances
			(project "com-express-7-baseboard"
				(path ""
					(reference "R179")
					(unit 1)
				)
			)
		)
	)
	(symbol
		(lib_id "antmicroMemory:M24C64-F_DFN8")
		(at 229.87 212.09 0)
		(unit 1)
		(exclude_from_sim no)
		(in_bom yes)
		(on_board yes)
		(dnp no)
		(property "Reference" "U31"
			(at 237.49 204.47 0)
			(effects
				(font
					(size 1.27 1.27)
					(thickness 0.15)
				)
			)
		)
		(property "Value" "M24C64-F_DFN8"
			(at 237.49 207.01 0)
			(effects
				(font
					(size 1.27 1.27)
					(thickness 0.15)
				)
				(hide yes)
			)
		)
		(property "Footprint" "antmicro-footprints:DFN-8-1EP_3x2mm_P0.5mm_EP1.36x1.46mm"
			(at 267.97 219.71 0)
			(effects
				(font
					(size 1.27 1.27)
					(thickness 0.15)
				)
				(justify left bottom)
				(hide yes)
			)
		)
		(property "Datasheet" "https://eu.mouser.com/datasheet/2/389/cd00259166-1797197.pdf"
			(at 267.97 222.25 0)
			(effects
				(font
					(size 1.27 1.27)
					(thickness 0.15)
				)
				(justify left bottom)
				(hide yes)
			)
		)
		(property "Description" ""
			(at 229.87 212.09 0)
			(effects
				(font
					(size 1.27 1.27)
				)
				(hide yes)
			)
		)
		(property "Manufacturer" "STMicroelectronics"
			(at 267.97 224.79 0)
			(effects
				(font
					(size 1.27 1.27)
					(thickness 0.15)
				)
				(justify left bottom)
				(hide yes)
			)
		)
		(property "MPN" "M24C64-FMC6TG"
			(at 229.87 208.28 0)
			(effects
				(font
					(size 1.27 1.27)
					(thickness 0.15)
				)
				(justify left bottom)
			)
		)
		(property "Author" "Antmicro"
			(at 267.97 229.87 0)
			(effects
				(font
					(size 1.27 1.27)
					(thickness 0.15)
				)
				(justify left bottom)
				(hide yes)
			)
		)
		(property "License" "Apache-2.0"
			(at 267.97 232.41 0)
			(effects
				(font
					(size 1.27 1.27)
					(thickness 0.15)
				)
				(justify left bottom)
				(hide yes)
			)
		)
		(pin "8"
		)
		(pin "5"
		)
		(pin "6"
		)
		(pin "9"
		)
		(pin "4"
		)
		(pin "1"
		)
		(pin "3"
		)
		(pin "7"
		)
		(pin "2"
		)
		(instances
			(project "com-express-7-baseboard"
				(path ""
					(reference "U31")
					(unit 1)
				)
			)
		)
	)
	(symbol
		(lib_id "antmicropower:GND")
		(at 259.08 215.9 0)
		(mirror y)
		(unit 1)
		(exclude_from_sim no)
		(in_bom yes)
		(on_board yes)
		(dnp no)
		(property "Reference" "#PWR0254"
			(at 250.19 218.44 0)
			(effects
				(font
					(size 1.27 1.27)
					(thickness 0.15)
				)
				(justify left bottom)
				(hide yes)
			)
		)
		(property "Value" "GND"
			(at 259.08 219.71 0)
			(effects
				(font
					(size 1.27 1.27)
					(thickness 0.15)
				)
			)
		)
		(property "Footprint" ""
			(at 250.19 223.52 0)
			(effects
				(font
					(size 1.27 1.27)
					(thickness 0.15)
				)
				(justify left bottom)
				(hide yes)
			)
		)
		(property "Datasheet" ""
			(at 250.19 228.6 0)
			(effects
				(font
					(size 1.27 1.27)
					(thickness 0.15)
				)
				(justify left bottom)
				(hide yes)
			)
		)
		(property "Description" ""
			(at 259.08 215.9 0)
			(effects
				(font
					(size 1.27 1.27)
				)
				(hide yes)
			)
		)
		(property "Author" "Antmicro"
			(at 250.19 223.52 0)
			(effects
				(font
					(size 1.27 1.27)
					(thickness 0.15)
				)
				(justify left bottom)
				(hide yes)
			)
		)
		(property "License" "Apache-2.0"
			(at 250.19 226.06 0)
			(effects
				(font
					(size 1.27 1.27)
					(thickness 0.15)
				)
				(justify left bottom)
				(hide yes)
			)
		)
		(pin "1"
		)
		(instances
			(project "com-express-7-baseboard"
				(path ""
					(reference "#PWR0254")
					(unit 1)
				)
			)
		)
	)
	(symbol
		(lib_id "antmicroResistors0402:R_2k2_0402")
		(at 116.84 68.58 90)
		(unit 1)
		(exclude_from_sim no)
		(in_bom yes)
		(on_board yes)
		(dnp no)
		(fields_autoplaced yes)
		(property "Reference" "R165"
			(at 118.11 64.77 90)
			(effects
				(font
					(size 1.27 1.27)
					(thickness 0.15)
				)
				(justify right)
			)
		)
		(property "Value" "R_2k2_0402"
			(at 129.54 48.26 0)
			(effects
				(font
					(size 1.27 1.27)
					(thickness 0.15)
				)
				(justify left bottom)
				(hide yes)
			)
		)
		(property "Footprint" "antmicro-footprints:R_0402_1005Metric"
			(at 132.08 48.26 0)
			(effects
				(font
					(size 1.27 1.27)
					(thickness 0.15)
				)
				(justify left bottom)
				(hide yes)
			)
		)
		(property "Datasheet" "https://www.bourns.com/docs/product-datasheets/cr.pdf"
			(at 134.62 48.26 0)
			(effects
				(font
					(size 1.27 1.27)
					(thickness 0.15)
				)
				(justify left bottom)
				(hide yes)
			)
		)
		(property "Description" ""
			(at 116.84 68.58 0)
			(effects
				(font
					(size 1.27 1.27)
				)
				(hide yes)
			)
		)
		(property "MPN" "CR0402-FX-2201GLF"
			(at 137.16 48.26 0)
			(effects
				(font
					(size 1.27 1.27)
					(thickness 0.15)
				)
				(justify left bottom)
				(hide yes)
			)
		)
		(property "Manufacturer" "Bourns"
			(at 139.7 48.26 0)
			(effects
				(font
					(size 1.27 1.27)
					(thickness 0.15)
				)
				(justify left bottom)
				(hide yes)
			)
		)
		(property "License" "Apache-2.0"
			(at 142.24 48.26 0)
			(effects
				(font
					(size 1.27 1.27)
					(thickness 0.15)
				)
				(justify left bottom)
				(hide yes)
			)
		)
		(property "Author" "Antmicro"
			(at 144.78 48.26 0)
			(effects
				(font
					(size 1.27 1.27)
					(thickness 0.15)
				)
				(justify left bottom)
				(hide yes)
			)
		)
		(property "Val" "2k2"
			(at 118.11 67.31 90)
			(effects
				(font
					(size 1.27 1.27)
					(thickness 0.15)
				)
				(justify right)
			)
		)
		(property "Tolerance" "1%"
			(at 127 48.26 0)
			(effects
				(font
					(size 1.27 1.27)
				)
				(justify left bottom)
				(hide yes)
			)
		)
		(property "Public" "False"
			(at 147.32 48.26 0)
			(effects
				(font
					(size 1.27 1.27)
				)
				(justify left bottom)
				(hide yes)
			)
		)
		(pin "1"
		)
		(pin "2"
		)
		(instances
			(project "com-express-7-baseboard"
				(path ""
					(reference "R165")
					(unit 1)
				)
			)
		)
	)
	(symbol
		(lib_id "antmicroResistors0402:R_1k_0402")
		(at 218.44 63.5 90)
		(unit 1)
		(exclude_from_sim no)
		(in_bom yes)
		(on_board yes)
		(dnp yes)
		(fields_autoplaced yes)
		(property "Reference" "R166"
			(at 220.98 59.69 90)
			(effects
				(font
					(size 1.27 1.27)
					(thickness 0.15)
				)
				(justify right)
			)
		)
		(property "Value" "R_1k_0402"
			(at 231.14 43.18 0)
			(effects
				(font
					(size 1.27 1.27)
					(thickness 0.15)
				)
				(justify left bottom)
				(hide yes)
			)
		)
		(property "Footprint" "antmicro-footprints:R_0402_1005Metric"
			(at 233.68 43.18 0)
			(effects
				(font
					(size 1.27 1.27)
					(thickness 0.15)
				)
				(justify left bottom)
				(hide yes)
			)
		)
		(property "Datasheet" "https://www.bourns.com/docs/product-datasheets/cr.pdf"
			(at 236.22 43.18 0)
			(effects
				(font
					(size 1.27 1.27)
					(thickness 0.15)
				)
				(justify left bottom)
				(hide yes)
			)
		)
		(property "Description" ""
			(at 218.44 63.5 0)
			(effects
				(font
					(size 1.27 1.27)
				)
				(hide yes)
			)
		)
		(property "MPN" "CR0402-FX-1001GLF"
			(at 238.76 43.18 0)
			(effects
				(font
					(size 1.27 1.27)
					(thickness 0.15)
				)
				(justify left bottom)
				(hide yes)
			)
		)
		(property "Manufacturer" "Bourns"
			(at 241.3 43.18 0)
			(effects
				(font
					(size 1.27 1.27)
					(thickness 0.15)
				)
				(justify left bottom)
				(hide yes)
			)
		)
		(property "License" "Apache-2.0"
			(at 243.84 43.18 0)
			(effects
				(font
					(size 1.27 1.27)
					(thickness 0.15)
				)
				(justify left bottom)
				(hide yes)
			)
		)
		(property "Author" "Antmicro"
			(at 246.38 43.18 0)
			(effects
				(font
					(size 1.27 1.27)
					(thickness 0.15)
				)
				(justify left bottom)
				(hide yes)
			)
		)
		(property "Val" "1k"
			(at 220.98 62.23 90)
			(effects
				(font
					(size 1.27 1.27)
					(thickness 0.15)
				)
				(justify right)
			)
		)
		(property "Tolerance" "1%"
			(at 228.6 43.18 0)
			(effects
				(font
					(size 1.27 1.27)
				)
				(justify left bottom)
				(hide yes)
			)
		)
		(property "Public" "False"
			(at 248.92 43.18 0)
			(effects
				(font
					(size 1.27 1.27)
				)
				(justify left bottom)
				(hide yes)
			)
		)
		(pin "1"
		)
		(pin "2"
		)
		(instances
			(project "com-express-7-baseboard"
				(path ""
					(reference "R166")
					(unit 1)
				)
			)
		)
	)
	(symbol
		(lib_id "antmicroTestPoints:TP_0.75mm_SMD")
		(at 76.2 127 0)
		(unit 1)
		(exclude_from_sim no)
		(in_bom no)
		(on_board yes)
		(dnp no)
		(fields_autoplaced yes)
		(property "Reference" "TP30"
			(at 81.28 127 0)
			(effects
				(font
					(size 1.27 1.27)
					(thickness 0.15)
				)
				(justify left)
			)
		)
		(property "Value" "TP_0.75mm_SMD"
			(at 86.995 130.81 0)
			(effects
				(font
					(size 1.27 1.27)
					(thickness 0.15)
				)
				(justify left bottom)
				(hide yes)
			)
		)
		(property "Footprint" "antmicro-footprints:TP_SMD_0.75mm"
			(at 86.995 133.35 0)
			(effects
				(font
					(size 1.27 1.27)
					(thickness 0.15)
				)
				(justify left bottom)
				(hide yes)
			)
		)
		(property "Datasheet" ""
			(at 93.98 139.7 0)
			(effects
				(font
					(size 1.27 1.27)
					(thickness 0.15)
				)
				(justify left bottom)
				(hide yes)
			)
		)
		(property "Description" ""
			(at 76.2 127 0)
			(effects
				(font
					(size 1.27 1.27)
				)
				(hide yes)
			)
		)
		(property "MPN" ""
			(at 86.995 138.43 0)
			(effects
				(font
					(size 1.27 1.27)
					(thickness 0.15)
				)
				(justify left bottom)
				(hide yes)
			)
		)
		(property "Manufacturer" ""
			(at 86.995 133.35 0)
			(effects
				(font
					(size 1.27 1.27)
					(thickness 0.15)
				)
				(justify left bottom)
				(hide yes)
			)
		)
		(property "Author" "Antmicro"
			(at 86.995 135.89 0)
			(effects
				(font
					(size 1.27 1.27)
					(thickness 0.15)
				)
				(justify left bottom)
				(hide yes)
			)
		)
		(property "License" "Apache-2.0"
			(at 86.995 138.43 0)
			(effects
				(font
					(size 1.27 1.27)
					(thickness 0.15)
				)
				(justify left bottom)
				(hide yes)
			)
		)
		(property "Public" "False"
			(at 86.36 140.97 0)
			(effects
				(font
					(size 1.27 1.27)
				)
				(justify left bottom)
				(hide yes)
			)
		)
		(pin "1"
		)
		(instances
			(project "com-express-7-baseboard"
				(path ""
					(reference "TP30")
					(unit 1)
				)
			)
		)
	)
	(symbol
		(lib_id "antmicropower:GND")
		(at 95.25 135.89 0)
		(unit 1)
		(exclude_from_sim no)
		(in_bom yes)
		(on_board yes)
		(dnp no)
		(property "Reference" "#PWR0229"
			(at 104.14 138.43 0)
			(effects
				(font
					(size 1.27 1.27)
					(thickness 0.15)
				)
				(justify left bottom)
				(hide yes)
			)
		)
		(property "Value" "GND"
			(at 99.06 137.16 0)
			(effects
				(font
					(size 1.27 1.27)
					(thickness 0.15)
				)
			)
		)
		(property "Footprint" ""
			(at 104.14 143.51 0)
			(effects
				(font
					(size 1.27 1.27)
					(thickness 0.15)
				)
				(justify left bottom)
				(hide yes)
			)
		)
		(property "Datasheet" ""
			(at 104.14 148.59 0)
			(effects
				(font
					(size 1.27 1.27)
					(thickness 0.15)
				)
				(justify left bottom)
				(hide yes)
			)
		)
		(property "Description" ""
			(at 95.25 135.89 0)
			(effects
				(font
					(size 1.27 1.27)
				)
				(hide yes)
			)
		)
		(property "Author" "Antmicro"
			(at 104.14 143.51 0)
			(effects
				(font
					(size 1.27 1.27)
					(thickness 0.15)
				)
				(justify left bottom)
				(hide yes)
			)
		)
		(property "License" "Apache-2.0"
			(at 104.14 146.05 0)
			(effects
				(font
					(size 1.27 1.27)
					(thickness 0.15)
				)
				(justify left bottom)
				(hide yes)
			)
		)
		(pin "1"
		)
		(instances
			(project "com-express-7-baseboard"
				(path ""
					(reference "#PWR0229")
					(unit 1)
				)
			)
		)
	)
	(symbol
		(lib_id "antmicropower:GND")
		(at 382.27 212.09 0)
		(unit 1)
		(exclude_from_sim no)
		(in_bom yes)
		(on_board yes)
		(dnp no)
		(property "Reference" "#PWR0270"
			(at 391.16 214.63 0)
			(effects
				(font
					(size 1.27 1.27)
					(thickness 0.15)
				)
				(justify left bottom)
				(hide yes)
			)
		)
		(property "Value" "GND"
			(at 382.27 215.9 0)
			(effects
				(font
					(size 1.27 1.27)
					(thickness 0.15)
				)
			)
		)
		(property "Footprint" ""
			(at 391.16 219.71 0)
			(effects
				(font
					(size 1.27 1.27)
					(thickness 0.15)
				)
				(justify left bottom)
				(hide yes)
			)
		)
		(property "Datasheet" ""
			(at 391.16 224.79 0)
			(effects
				(font
					(size 1.27 1.27)
					(thickness 0.15)
				)
				(justify left bottom)
				(hide yes)
			)
		)
		(property "Description" ""
			(at 382.27 212.09 0)
			(effects
				(font
					(size 1.27 1.27)
				)
				(hide yes)
			)
		)
		(property "Author" "Antmicro"
			(at 391.16 219.71 0)
			(effects
				(font
					(size 1.27 1.27)
					(thickness 0.15)
				)
				(justify left bottom)
				(hide yes)
			)
		)
		(property "License" "Apache-2.0"
			(at 391.16 222.25 0)
			(effects
				(font
					(size 1.27 1.27)
					(thickness 0.15)
				)
				(justify left bottom)
				(hide yes)
			)
		)
		(pin "1"
		)
		(instances
			(project "com-express-7-baseboard"
				(path ""
					(reference "#PWR0270")
					(unit 1)
				)
			)
		)
	)
	(symbol
		(lib_id "antmicroResistors0402:R_10k_0402")
		(at 95.25 162.56 0)
		(unit 1)
		(exclude_from_sim no)
		(in_bom yes)
		(on_board yes)
		(dnp no)
		(property "Reference" "R162"
			(at 92.71 163.83 0)
			(effects
				(font
					(size 1.27 1.27)
					(thickness 0.15)
				)
			)
		)
		(property "Value" "R_10k_0402"
			(at 115.57 175.26 0)
			(effects
				(font
					(size 1.27 1.27)
					(thickness 0.15)
				)
				(justify left bottom)
				(hide yes)
			)
		)
		(property "Footprint" "antmicro-footprints:R_0402_1005Metric"
			(at 115.57 177.8 0)
			(effects
				(font
					(size 1.27 1.27)
					(thickness 0.15)
				)
				(justify left bottom)
				(hide yes)
			)
		)
		(property "Datasheet" "https://www.bourns.com/docs/product-datasheets/cr.pdf"
			(at 115.57 180.34 0)
			(effects
				(font
					(size 1.27 1.27)
					(thickness 0.15)
				)
				(justify left bottom)
				(hide yes)
			)
		)
		(property "Description" ""
			(at 95.25 162.56 0)
			(effects
				(font
					(size 1.27 1.27)
				)
				(hide yes)
			)
		)
		(property "MPN" "CR0402-FX-1002GLF"
			(at 115.57 182.88 0)
			(effects
				(font
					(size 1.27 1.27)
					(thickness 0.15)
				)
				(justify left bottom)
				(hide yes)
			)
		)
		(property "Manufacturer" "Bourns"
			(at 115.57 185.42 0)
			(effects
				(font
					(size 1.27 1.27)
					(thickness 0.15)
				)
				(justify left bottom)
				(hide yes)
			)
		)
		(property "License" "Apache-2.0"
			(at 115.57 187.96 0)
			(effects
				(font
					(size 1.27 1.27)
					(thickness 0.15)
				)
				(justify left bottom)
				(hide yes)
			)
		)
		(property "Author" "Antmicro"
			(at 115.57 190.5 0)
			(effects
				(font
					(size 1.27 1.27)
					(thickness 0.15)
				)
				(justify left bottom)
				(hide yes)
			)
		)
		(property "Val" "10k"
			(at 101.6 163.83 0)
			(effects
				(font
					(size 1.27 1.27)
					(thickness 0.15)
				)
			)
		)
		(property "Tolerance" "1%"
			(at 115.57 172.72 0)
			(effects
				(font
					(size 1.27 1.27)
				)
				(justify left bottom)
				(hide yes)
			)
		)
		(property "Public" "False"
			(at 115.57 193.04 0)
			(effects
				(font
					(size 1.27 1.27)
				)
				(justify left bottom)
				(hide yes)
			)
		)
		(pin "1"
		)
		(pin "2"
		)
		(instances
			(project "com-express-7-baseboard"
				(path ""
					(reference "R162")
					(unit 1)
				)
			)
		)
	)
	(symbol
		(lib_id "antmicropower:+3V3_AON")
		(at 138.43 55.88 0)
		(unit 1)
		(exclude_from_sim no)
		(in_bom yes)
		(on_board yes)
		(dnp no)
		(property "Reference" "#PWR0240"
			(at 138.43 59.69 0)
			(effects
				(font
					(size 1.27 1.27)
				)
				(hide yes)
			)
		)
		(property "Value" "+3V3_AON"
			(at 138.43 52.07 0)
			(effects
				(font
					(size 1.27 1.27)
				)
			)
		)
		(property "Footprint" ""
			(at 138.43 55.88 0)
			(effects
				(font
					(size 1.27 1.27)
				)
				(hide yes)
			)
		)
		(property "Datasheet" ""
			(at 138.43 55.88 0)
			(effects
				(font
					(size 1.27 1.27)
				)
				(hide yes)
			)
		)
		(property "Description" ""
			(at 138.43 55.88 0)
			(effects
				(font
					(size 1.27 1.27)
				)
				(hide yes)
			)
		)
		(pin "1"
		)
		(instances
			(project "com-express-7-baseboard"
				(path ""
					(reference "#PWR0240")
					(unit 1)
				)
			)
		)
	)
	(symbol
		(lib_id "antmicropower:GND")
		(at 381 219.71 0)
		(unit 1)
		(exclude_from_sim no)
		(in_bom yes)
		(on_board yes)
		(dnp no)
		(property "Reference" "#PWR0269"
			(at 389.89 222.25 0)
			(effects
				(font
					(size 1.27 1.27)
					(thickness 0.15)
				)
				(justify left bottom)
				(hide yes)
			)
		)
		(property "Value" "GND"
			(at 381 223.52 0)
			(effects
				(font
					(size 1.27 1.27)
					(thickness 0.15)
				)
			)
		)
		(property "Footprint" ""
			(at 389.89 227.33 0)
			(effects
				(font
					(size 1.27 1.27)
					(thickness 0.15)
				)
				(justify left bottom)
				(hide yes)
			)
		)
		(property "Datasheet" ""
			(at 389.89 232.41 0)
			(effects
				(font
					(size 1.27 1.27)
					(thickness 0.15)
				)
				(justify left bottom)
				(hide yes)
			)
		)
		(property "Description" ""
			(at 381 219.71 0)
			(effects
				(font
					(size 1.27 1.27)
				)
				(hide yes)
			)
		)
		(property "Author" "Antmicro"
			(at 389.89 227.33 0)
			(effects
				(font
					(size 1.27 1.27)
					(thickness 0.15)
				)
				(justify left bottom)
				(hide yes)
			)
		)
		(property "License" "Apache-2.0"
			(at 389.89 229.87 0)
			(effects
				(font
					(size 1.27 1.27)
					(thickness 0.15)
				)
				(justify left bottom)
				(hide yes)
			)
		)
		(pin "1"
		)
		(instances
			(project "com-express-7-baseboard"
				(path ""
					(reference "#PWR0269")
					(unit 1)
				)
			)
		)
	)
	(symbol
		(lib_id "antmicropower:GND")
		(at 116.84 128.27 0)
		(unit 1)
		(exclude_from_sim no)
		(in_bom yes)
		(on_board yes)
		(dnp no)
		(property "Reference" "#PWR0237"
			(at 125.73 130.81 0)
			(effects
				(font
					(size 1.27 1.27)
					(thickness 0.15)
				)
				(justify left bottom)
				(hide yes)
			)
		)
		(property "Value" "GND"
			(at 116.84 132.08 0)
			(effects
				(font
					(size 1.27 1.27)
					(thickness 0.15)
				)
			)
		)
		(property "Footprint" ""
			(at 125.73 135.89 0)
			(effects
				(font
					(size 1.27 1.27)
					(thickness 0.15)
				)
				(justify left bottom)
				(hide yes)
			)
		)
		(property "Datasheet" ""
			(at 125.73 140.97 0)
			(effects
				(font
					(size 1.27 1.27)
					(thickness 0.15)
				)
				(justify left bottom)
				(hide yes)
			)
		)
		(property "Description" ""
			(at 116.84 128.27 0)
			(effects
				(font
					(size 1.27 1.27)
				)
				(hide yes)
			)
		)
		(property "Author" "Antmicro"
			(at 125.73 135.89 0)
			(effects
				(font
					(size 1.27 1.27)
					(thickness 0.15)
				)
				(justify left bottom)
				(hide yes)
			)
		)
		(property "License" "Apache-2.0"
			(at 125.73 138.43 0)
			(effects
				(font
					(size 1.27 1.27)
					(thickness 0.15)
				)
				(justify left bottom)
				(hide yes)
			)
		)
		(pin "1"
		)
		(instances
			(project "com-express-7-baseboard"
				(path ""
					(reference "#PWR0237")
					(unit 1)
				)
			)
		)
	)
	(symbol
		(lib_id "antmicropower:GND")
		(at 256.54 118.11 0)
		(unit 1)
		(exclude_from_sim no)
		(in_bom yes)
		(on_board yes)
		(dnp no)
		(property "Reference" "#PWR0249"
			(at 265.43 120.65 0)
			(effects
				(font
					(size 1.27 1.27)
					(thickness 0.15)
				)
				(justify left bottom)
				(hide yes)
			)
		)
		(property "Value" "GND"
			(at 256.54 121.92 0)
			(effects
				(font
					(size 1.27 1.27)
					(thickness 0.15)
				)
			)
		)
		(property "Footprint" ""
			(at 265.43 125.73 0)
			(effects
				(font
					(size 1.27 1.27)
					(thickness 0.15)
				)
				(justify left bottom)
				(hide yes)
			)
		)
		(property "Datasheet" ""
			(at 265.43 130.81 0)
			(effects
				(font
					(size 1.27 1.27)
					(thickness 0.15)
				)
				(justify left bottom)
				(hide yes)
			)
		)
		(property "Description" ""
			(at 256.54 118.11 0)
			(effects
				(font
					(size 1.27 1.27)
				)
				(hide yes)
			)
		)
		(property "Author" "Antmicro"
			(at 265.43 125.73 0)
			(effects
				(font
					(size 1.27 1.27)
					(thickness 0.15)
				)
				(justify left bottom)
				(hide yes)
			)
		)
		(property "License" "Apache-2.0"
			(at 265.43 128.27 0)
			(effects
				(font
					(size 1.27 1.27)
					(thickness 0.15)
				)
				(justify left bottom)
				(hide yes)
			)
		)
		(pin "1"
		)
		(instances
			(project "com-express-7-baseboard"
				(path ""
					(reference "#PWR0249")
					(unit 1)
				)
			)
		)
	)
	(symbol
		(lib_id "antmicroB2BConnectors:Plug_Bus_CE7_EPT_401-51501-51")
		(at 76.2 213.36 0)
		(unit 12)
		(exclude_from_sim no)
		(in_bom yes)
		(on_board yes)
		(dnp no)
		(fields_autoplaced yes)
		(property "Reference" "J12"
			(at 57.15 205.74 0)
			(effects
				(font
					(size 1.27 1.27)
					(thickness 0.15)
				)
			)
		)
		(property "Value" "Plug_Bus_CE7_EPT_401-51501-51"
			(at 129.54 226.06 0)
			(effects
				(font
					(size 1.27 1.27)
					(thickness 0.15)
				)
				(justify left bottom)
				(hide yes)
			)
		)
		(property "Footprint" "antmicro-footprints:EPT_401-51501-51"
			(at 129.54 228.6 0)
			(effects
				(font
					(size 1.27 1.27)
					(thickness 0.15)
				)
				(justify left bottom)
				(hide yes)
			)
		)
		(property "Datasheet" "https://www.farnell.com/datasheets/1905093.pdf"
			(at 129.54 231.14 0)
			(effects
				(font
					(size 1.27 1.27)
					(thickness 0.15)
				)
				(justify left bottom)
				(hide yes)
			)
		)
		(property "Description" ""
			(at 76.2 213.36 0)
			(effects
				(font
					(size 1.27 1.27)
				)
				(hide yes)
			)
		)
		(property "Author" "Antmicro"
			(at 129.54 233.68 0)
			(effects
				(font
					(size 1.27 1.27)
					(thickness 0.15)
				)
				(justify left bottom)
				(hide yes)
			)
		)
		(property "License" "Apache-2.0"
			(at 129.54 236.22 0)
			(effects
				(font
					(size 1.27 1.27)
					(thickness 0.15)
				)
				(justify left bottom)
				(hide yes)
			)
		)
		(property "Manufacturer" "ept"
			(at 129.54 218.44 0)
			(effects
				(font
					(size 1.27 1.27)
					(thickness 0.15)
				)
				(justify left bottom)
				(hide yes)
			)
		)
		(property "MPN" "401-51501-51"
			(at 57.15 208.28 0)
			(effects
				(font
					(size 1.27 1.27)
					(thickness 0.15)
				)
			)
		)
		(pin "C91"
		)
		(pin "C92"
		)
		(pin "A15"
		)
		(pin "A91"
		)
		(pin "C34"
		)
		(pin "C35"
		)
		(pin "D22"
		)
		(pin "D23"
		)
		(pin "D55"
		)
		(pin "D56"
		)
		(pin "C55"
		)
		(pin "C56"
		)
		(pin "C71"
		)
		(pin "C72"
		)
		(pin "C32"
		)
		(pin "C33"
		)
		(pin "B6"
		)
		(pin "B58"
		)
		(pin "B59"
		)
		(pin "D5"
		)
		(pin "D51"
		)
		(pin "A29"
		)
		(pin "D46"
		)
		(pin "D47"
		)
		(pin "C105"
		)
		(pin "C106"
		)
		(pin "A16"
		)
		(pin "B22"
		)
		(pin "B51"
		)
		(pin "B30"
		)
		(pin "A44"
		)
		(pin "C51"
		)
		(pin "C60"
		)
		(pin "A81"
		)
		(pin "A82"
		)
		(pin "D90"
		)
		(pin "D93"
		)
		(pin "B68"
		)
		(pin "B69"
		)
		(pin "C103"
		)
		(pin "C104"
		)
		(pin "C58"
		)
		(pin "C59"
		)
		(pin "D84"
		)
		(pin "D87"
		)
		(pin "A30"
		)
		(pin "B29"
		)
		(pin "A41"
		)
		(pin "C40"
		)
		(pin "C42"
		)
		(pin "D80"
		)
		(pin "D83"
		)
		(pin "B103"
		)
		(pin "A102"
		)
		(pin "C101"
		)
		(pin "C102"
		)
		(pin "D11"
		)
		(pin "D110"
		)
		(pin "B37"
		)
		(pin "B45"
		)
		(pin "C61"
		)
		(pin "C62"
		)
		(pin "A42"
		)
		(pin "B36"
		)
		(pin "B57"
		)
		(pin "D12"
		)
		(pin "D44"
		)
		(pin "D48"
		)
		(pin "B32"
		)
		(pin "B107"
		)
		(pin "B108"
		)
		(pin "B110"
		)
		(pin "B101"
		)
		(pin "C63"
		)
		(pin "C64"
		)
		(pin "B50"
		)
		(pin "A87"
		)
		(pin "A86"
		)
		(pin "B27"
		)
		(pin "D17"
		)
		(pin "D24"
		)
		(pin "D26"
		)
		(pin "D27"
		)
		(pin "A47"
		)
		(pin "C81"
		)
		(pin "C82"
		)
		(pin "C68"
		)
		(pin "C69"
		)
		(pin "A74"
		)
		(pin "A48"
		)
		(pin "A57"
		)
		(pin "A43"
		)
		(pin "A31"
		)
		(pin "D29"
		)
		(pin "D30"
		)
		(pin "C36"
		)
		(pin "C37"
		)
		(pin "C3"
		)
		(pin "A35"
		)
		(pin "A34"
		)
		(pin "B7"
		)
		(pin "B46"
		)
		(pin "B1"
		)
		(pin "B63"
		)
		(pin "A51"
		)
		(pin "A99"
		)
		(pin "B17"
		)
		(pin "C13"
		)
		(pin "C4"
		)
		(pin "B102"
		)
		(pin "C38"
		)
		(pin "C39"
		)
		(pin "B3"
		)
		(pin "A90"
		)
		(pin "A72"
		)
		(pin "B84"
		)
		(pin "D19"
		)
		(pin "D20"
		)
		(pin "D43"
		)
		(pin "D45"
		)
		(pin "A77"
		)
		(pin "A78"
		)
		(pin "B38"
		)
		(pin "B86"
		)
		(pin "D77"
		)
		(pin "D8"
		)
		(pin "A32"
		)
		(pin "B85"
		)
		(pin "D73"
		)
		(pin "D76"
		)
		(pin "D63"
		)
		(pin "D64"
		)
		(pin "D67"
		)
		(pin "D70"
		)
		(pin "B83"
		)
		(pin "D81"
		)
		(pin "D82"
		)
		(pin "B41"
		)
		(pin "D49"
		)
		(pin "D50"
		)
		(pin "A75"
		)
		(pin "D2"
		)
		(pin "D21"
		)
		(pin "C78"
		)
		(pin "C79"
		)
		(pin "B19"
		)
		(pin "B39"
		)
		(pin "A12"
		)
		(pin "B66"
		)
		(pin "D4"
		)
		(pin "D85"
		)
		(pin "D86"
		)
		(pin "A105"
		)
		(pin "B90"
		)
		(pin "A22"
		)
		(pin "A109"
		)
		(pin "B88"
		)
		(pin "B14"
		)
		(pin "B71"
		)
		(pin "B52"
		)
		(pin "B53"
		)
		(pin "D7"
		)
		(pin "A108"
		)
		(pin "C85"
		)
		(pin "C86"
		)
		(pin "B61"
		)
		(pin "B62"
		)
		(pin "D68"
		)
		(pin "D69"
		)
		(pin "A88"
		)
		(pin "A89"
		)
		(pin "D6"
		)
		(pin "C7"
		)
		(pin "B33"
		)
		(pin "D88"
		)
		(pin "D89"
		)
		(pin "B26"
		)
		(pin "A76"
		)
		(pin "D101"
		)
		(pin "D102"
		)
		(pin "B12"
		)
		(pin "C15"
		)
		(pin "C16"
		)
		(pin "A18"
		)
		(pin "A13"
		)
		(pin "A66"
		)
		(pin "C26"
		)
		(pin "C27"
		)
		(pin "A101"
		)
		(pin "A17"
		)
		(pin "B96"
		)
		(pin "C22"
		)
		(pin "C23"
		)
		(pin "A79"
		)
		(pin "A54"
		)
		(pin "C41"
		)
		(pin "C44"
		)
		(pin "A100"
		)
		(pin "A67"
		)
		(pin "A10"
		)
		(pin "A14"
		)
		(pin "C6"
		)
		(pin "A84"
		)
		(pin "B91"
		)
		(pin "C29"
		)
		(pin "C30"
		)
		(pin "A37"
		)
		(pin "A39"
		)
		(pin "B10"
		)
		(pin "B34"
		)
		(pin "C54"
		)
		(pin "C57"
		)
		(pin "B64"
		)
		(pin "B65"
		)
		(pin "A58"
		)
		(pin "A59"
		)
		(pin "B92"
		)
		(pin "C43"
		)
		(pin "C45"
		)
		(pin "A97"
		)
		(pin "A11"
		)
		(pin "A61"
		)
		(pin "A62"
		)
		(pin "B48"
		)
		(pin "B54"
		)
		(pin "D71"
		)
		(pin "D72"
		)
		(pin "A26"
		)
		(pin "A36"
		)
		(pin "D31"
		)
		(pin "D36"
		)
		(pin "B76"
		)
		(pin "B21"
		)
		(pin "B24"
		)
		(pin "B94"
		)
		(pin "D3"
		)
		(pin "B79"
		)
		(pin "A85"
		)
		(pin "A23"
		)
		(pin "A25"
		)
		(pin "A24"
		)
		(pin "D14"
		)
		(pin "D18"
		)
		(pin "B15"
		)
		(pin "A107"
		)
		(pin "A98"
		)
		(pin "D9"
		)
		(pin "B44"
		)
		(pin "A4"
		)
		(pin "C28"
		)
		(pin "C31"
		)
		(pin "A9"
		)
		(pin "C49"
		)
		(pin "C50"
		)
		(pin "A83"
		)
		(pin "A110"
		)
		(pin "D52"
		)
		(pin "D53"
		)
		(pin "A40"
		)
		(pin "A71"
		)
		(pin "D98"
		)
		(pin "D99"
		)
		(pin "D40"
		)
		(pin "D42"
		)
		(pin "D37"
		)
		(pin "D41"
		)
		(pin "C109"
		)
		(pin "C11"
		)
		(pin "A106"
		)
		(pin "A3"
		)
		(pin "B109"
		)
		(pin "B40"
		)
		(pin "C70"
		)
		(pin "C73"
		)
		(pin "D13"
		)
		(pin "A1"
		)
		(pin "A46"
		)
		(pin "A20"
		)
		(pin "A104"
		)
		(pin "C9"
		)
		(pin "C110"
		)
		(pin "C14"
		)
		(pin "B23"
		)
		(pin "A93"
		)
		(pin "B89"
		)
		(pin "B87"
		)
		(pin "D54"
		)
		(pin "D60"
		)
		(pin "A21"
		)
		(pin "B93"
		)
		(pin "A70"
		)
		(pin "A60"
		)
		(pin "B97"
		)
		(pin "B95"
		)
		(pin "D38"
		)
		(pin "D39"
		)
		(pin "A50"
		)
		(pin "A52"
		)
		(pin "A53"
		)
		(pin "D91"
		)
		(pin "D92"
		)
		(pin "C67"
		)
		(pin "D57"
		)
		(pin "A96"
		)
		(pin "A92"
		)
		(pin "B70"
		)
		(pin "C46"
		)
		(pin "C47"
		)
		(pin "B4"
		)
		(pin "A64"
		)
		(pin "A65"
		)
		(pin "B43"
		)
		(pin "C21"
		)
		(pin "C25"
		)
		(pin "B42"
		)
		(pin "C19"
		)
		(pin "C20"
		)
		(pin "C18"
		)
		(pin "C2"
		)
		(pin "C107"
		)
		(pin "C108"
		)
		(pin "B35"
		)
		(pin "A28"
		)
		(pin "B11"
		)
		(pin "A103"
		)
		(pin "C97"
		)
		(pin "D1"
		)
		(pin "B98"
		)
		(pin "A19"
		)
		(pin "A68"
		)
		(pin "A69"
		)
		(pin "B55"
		)
		(pin "B56"
		)
		(pin "A8"
		)
		(pin "A33"
		)
		(pin "A95"
		)
		(pin "D96"
		)
		(pin "D97"
		)
		(pin "B31"
		)
		(pin "B105"
		)
		(pin "B100"
		)
		(pin "C65"
		)
		(pin "C66"
		)
		(pin "B104"
		)
		(pin "D61"
		)
		(pin "D62"
		)
		(pin "D78"
		)
		(pin "D79"
		)
		(pin "C83"
		)
		(pin "C84"
		)
		(pin "D74"
		)
		(pin "D75"
		)
		(pin "A45"
		)
		(pin "D106"
		)
		(pin "D107"
		)
		(pin "C8"
		)
		(pin "C80"
		)
		(pin "C87"
		)
		(pin "C90"
		)
		(pin "D58"
		)
		(pin "D59"
		)
		(pin "D104"
		)
		(pin "D105"
		)
		(pin "C93"
		)
		(pin "C96"
		)
		(pin "B73"
		)
		(pin "D108"
		)
		(pin "D109"
		)
		(pin "B20"
		)
		(pin "A27"
		)
		(pin "D34"
		)
		(pin "D35"
		)
		(pin "C17"
		)
		(pin "C24"
		)
		(pin "B49"
		)
		(pin "A6"
		)
		(pin "B5"
		)
		(pin "B99"
		)
		(pin "B25"
		)
		(pin "D94"
		)
		(pin "D95"
		)
		(pin "B106"
		)
		(pin "B67"
		)
		(pin "A2"
		)
		(pin "B13"
		)
		(pin "A49"
		)
		(pin "C52"
		)
		(pin "C53"
		)
		(pin "B72"
		)
		(pin "C94"
		)
		(pin "C95"
		)
		(pin "B74"
		)
		(pin "D10"
		)
		(pin "B75"
		)
		(pin "B77"
		)
		(pin "C98"
		)
		(pin "C99"
		)
		(pin "A7"
		)
		(pin "C88"
		)
		(pin "C89"
		)
		(pin "C10"
		)
		(pin "B78"
		)
		(pin "B81"
		)
		(pin "B28"
		)
		(pin "A63"
		)
		(pin "C76"
		)
		(pin "C77"
		)
		(pin "A55"
		)
		(pin "A56"
		)
		(pin "C48"
		)
		(pin "C5"
		)
		(pin "A5"
		)
		(pin "C1"
		)
		(pin "C100"
		)
		(pin "B47"
		)
		(pin "C74"
		)
		(pin "C75"
		)
		(pin "C12"
		)
		(pin "B80"
		)
		(pin "D15"
		)
		(pin "D16"
		)
		(pin "D100"
		)
		(pin "D103"
		)
		(pin "B2"
		)
		(pin "B9"
		)
		(pin "A94"
		)
		(pin "B82"
		)
		(pin "D25"
		)
		(pin "D28"
		)
		(pin "B16"
		)
		(pin "D65"
		)
		(pin "D66"
		)
		(pin "D32"
		)
		(pin "D33"
		)
		(pin "B8"
		)
		(pin "B60"
		)
		(pin "A38"
		)
		(pin "A73"
		)
		(pin "A80"
		)
		(pin "B18"
		)
		(pin "MP"
		)
		(instances
			(project "com-express-7-baseboard"
				(path ""
					(reference "J12")
					(unit 12)
				)
			)
		)
	)
	(symbol
		(lib_id "antmicroShuntsJumpers:Jumper_1x2_P2.54mm")
		(at 383.54 238.76 0)
		(unit 1)
		(exclude_from_sim no)
		(in_bom yes)
		(on_board yes)
		(dnp no)
		(property "Reference" "JP2"
			(at 382.27 234.95 0)
			(effects
				(font
					(size 1.27 1.27)
				)
				(justify left)
			)
		)
		(property "Value" "Jumper_1x2_P2.54mm"
			(at 379.73 237.49 0)
			(effects
				(font
					(size 1.27 1.27)
				)
				(justify left)
			)
		)
		(property "Footprint" "antmicro-footprints:Jumper_1x2_P2.54mm"
			(at 383.54 241.3 0)
			(effects
				(font
					(size 1.27 1.27)
				)
				(hide yes)
			)
		)
		(property "Datasheet" "https://www.tme.eu/en/details/jumper-w/pin-headers/ninigi/"
			(at 383.54 238.76 0)
			(effects
				(font
					(size 1.27 1.27)
				)
				(hide yes)
			)
		)
		(property "Description" ""
			(at 383.54 238.76 0)
			(effects
				(font
					(size 1.27 1.27)
				)
				(hide yes)
			)
		)
		(property "MPN" "JUMPER-W"
			(at 383.54 243.84 0)
			(effects
				(font
					(size 1.27 1.27)
				)
				(hide yes)
			)
		)
		(property "Manufacturer" "Ninigi"
			(at 383.54 245.745 0)
			(effects
				(font
					(size 1.27 1.27)
				)
				(hide yes)
			)
		)
		(property "License" "Apache-2.0"
			(at 383.54 249.555 0)
			(effects
				(font
					(size 1.27 1.27)
				)
				(hide yes)
			)
		)
		(property "Author" "Antmicro"
			(at 383.54 247.65 0)
			(effects
				(font
					(size 1.27 1.27)
				)
				(hide yes)
			)
		)
		(instances
			(project "com-express-7-baseboard"
				(path ""
					(reference "JP2")
					(unit 1)
				)
			)
		)
	)
	(symbol
		(lib_id "antmicropower:GND")
		(at 78.74 83.82 0)
		(unit 1)
		(exclude_from_sim no)
		(in_bom yes)
		(on_board yes)
		(dnp no)
		(property "Reference" "#PWR0225"
			(at 87.63 86.36 0)
			(effects
				(font
					(size 1.27 1.27)
					(thickness 0.15)
				)
				(justify left bottom)
				(hide yes)
			)
		)
		(property "Value" "GND"
			(at 78.74 87.63 0)
			(effects
				(font
					(size 1.27 1.27)
					(thickness 0.15)
				)
			)
		)
		(property "Footprint" ""
			(at 87.63 91.44 0)
			(effects
				(font
					(size 1.27 1.27)
					(thickness 0.15)
				)
				(justify left bottom)
				(hide yes)
			)
		)
		(property "Datasheet" ""
			(at 87.63 96.52 0)
			(effects
				(font
					(size 1.27 1.27)
					(thickness 0.15)
				)
				(justify left bottom)
				(hide yes)
			)
		)
		(property "Description" ""
			(at 78.74 83.82 0)
			(effects
				(font
					(size 1.27 1.27)
				)
				(hide yes)
			)
		)
		(property "Author" "Antmicro"
			(at 87.63 91.44 0)
			(effects
				(font
					(size 1.27 1.27)
					(thickness 0.15)
				)
				(justify left bottom)
				(hide yes)
			)
		)
		(property "License" "Apache-2.0"
			(at 87.63 93.98 0)
			(effects
				(font
					(size 1.27 1.27)
					(thickness 0.15)
				)
				(justify left bottom)
				(hide yes)
			)
		)
		(pin "1"
		)
		(instances
			(project "com-express-7-baseboard"
				(path ""
					(reference "#PWR0225")
					(unit 1)
				)
			)
		)
	)
	(symbol
		(lib_id "antmicroTestPoints:TP_0.75mm_SMD")
		(at 76.2 165.1 0)
		(unit 1)
		(exclude_from_sim no)
		(in_bom no)
		(on_board yes)
		(dnp no)
		(fields_autoplaced yes)
		(property "Reference" "TP34"
			(at 81.28 165.1 0)
			(effects
				(font
					(size 1.27 1.27)
					(thickness 0.15)
				)
				(justify left)
			)
		)
		(property "Value" "TP_0.75mm_SMD"
			(at 86.995 168.91 0)
			(effects
				(font
					(size 1.27 1.27)
					(thickness 0.15)
				)
				(justify left bottom)
				(hide yes)
			)
		)
		(property "Footprint" "antmicro-footprints:TP_SMD_0.75mm"
			(at 86.995 171.45 0)
			(effects
				(font
					(size 1.27 1.27)
					(thickness 0.15)
				)
				(justify left bottom)
				(hide yes)
			)
		)
		(property "Datasheet" ""
			(at 93.98 177.8 0)
			(effects
				(font
					(size 1.27 1.27)
					(thickness 0.15)
				)
				(justify left bottom)
				(hide yes)
			)
		)
		(property "Description" ""
			(at 76.2 165.1 0)
			(effects
				(font
					(size 1.27 1.27)
				)
				(hide yes)
			)
		)
		(property "MPN" ""
			(at 86.995 176.53 0)
			(effects
				(font
					(size 1.27 1.27)
					(thickness 0.15)
				)
				(justify left bottom)
				(hide yes)
			)
		)
		(property "Manufacturer" ""
			(at 86.995 171.45 0)
			(effects
				(font
					(size 1.27 1.27)
					(thickness 0.15)
				)
				(justify left bottom)
				(hide yes)
			)
		)
		(property "Author" "Antmicro"
			(at 86.995 173.99 0)
			(effects
				(font
					(size 1.27 1.27)
					(thickness 0.15)
				)
				(justify left bottom)
				(hide yes)
			)
		)
		(property "License" "Apache-2.0"
			(at 86.995 176.53 0)
			(effects
				(font
					(size 1.27 1.27)
					(thickness 0.15)
				)
				(justify left bottom)
				(hide yes)
			)
		)
		(property "Public" "False"
			(at 86.36 179.07 0)
			(effects
				(font
					(size 1.27 1.27)
				)
				(justify left bottom)
				(hide yes)
			)
		)
		(pin "1"
		)
		(instances
			(project "com-express-7-baseboard"
				(path ""
					(reference "TP34")
					(unit 1)
				)
			)
		)
	)
	(symbol
		(lib_id "antmicroTestPoints:TP_0.75mm_SMD")
		(at 76.2 187.96 0)
		(unit 1)
		(exclude_from_sim no)
		(in_bom no)
		(on_board yes)
		(dnp no)
		(fields_autoplaced yes)
		(property "Reference" "TP40"
			(at 81.28 187.96 0)
			(effects
				(font
					(size 1.27 1.27)
					(thickness 0.15)
				)
				(justify left)
			)
		)
		(property "Value" "TP_0.75mm_SMD"
			(at 86.995 191.77 0)
			(effects
				(font
					(size 1.27 1.27)
					(thickness 0.15)
				)
				(justify left bottom)
				(hide yes)
			)
		)
		(property "Footprint" "antmicro-footprints:TP_SMD_0.75mm"
			(at 86.995 194.31 0)
			(effects
				(font
					(size 1.27 1.27)
					(thickness 0.15)
				)
				(justify left bottom)
				(hide yes)
			)
		)
		(property "Datasheet" ""
			(at 93.98 200.66 0)
			(effects
				(font
					(size 1.27 1.27)
					(thickness 0.15)
				)
				(justify left bottom)
				(hide yes)
			)
		)
		(property "Description" ""
			(at 76.2 187.96 0)
			(effects
				(font
					(size 1.27 1.27)
				)
				(hide yes)
			)
		)
		(property "MPN" ""
			(at 86.995 199.39 0)
			(effects
				(font
					(size 1.27 1.27)
					(thickness 0.15)
				)
				(justify left bottom)
				(hide yes)
			)
		)
		(property "Manufacturer" ""
			(at 86.995 194.31 0)
			(effects
				(font
					(size 1.27 1.27)
					(thickness 0.15)
				)
				(justify left bottom)
				(hide yes)
			)
		)
		(property "Author" "Antmicro"
			(at 86.995 196.85 0)
			(effects
				(font
					(size 1.27 1.27)
					(thickness 0.15)
				)
				(justify left bottom)
				(hide yes)
			)
		)
		(property "License" "Apache-2.0"
			(at 86.995 199.39 0)
			(effects
				(font
					(size 1.27 1.27)
					(thickness 0.15)
				)
				(justify left bottom)
				(hide yes)
			)
		)
		(property "Public" "False"
			(at 86.36 201.93 0)
			(effects
				(font
					(size 1.27 1.27)
				)
				(justify left bottom)
				(hide yes)
			)
		)
		(pin "1"
		)
		(instances
			(project "com-express-7-baseboard"
				(path ""
					(reference "TP40")
					(unit 1)
				)
			)
		)
	)
	(symbol
		(lib_id "antmicroResistors0402:R_100k_0402")
		(at 259.08 81.28 90)
		(unit 1)
		(exclude_from_sim no)
		(in_bom yes)
		(on_board yes)
		(dnp yes)
		(fields_autoplaced yes)
		(property "Reference" "R173"
			(at 256.54 77.47 90)
			(effects
				(font
					(size 1.27 1.27)
					(thickness 0.15)
				)
				(justify left)
			)
		)
		(property "Value" "R_100k_0402"
			(at 271.78 60.96 0)
			(effects
				(font
					(size 1.27 1.27)
					(thickness 0.15)
				)
				(justify left bottom)
				(hide yes)
			)
		)
		(property "Footprint" "antmicro-footprints:R_0402_1005Metric"
			(at 274.32 60.96 0)
			(effects
				(font
					(size 1.27 1.27)
					(thickness 0.15)
				)
				(justify left bottom)
				(hide yes)
			)
		)
		(property "Datasheet" "https://www.bourns.com/docs/product-datasheets/cr.pdf"
			(at 276.86 60.96 0)
			(effects
				(font
					(size 1.27 1.27)
					(thickness 0.15)
				)
				(justify left bottom)
				(hide yes)
			)
		)
		(property "Description" ""
			(at 259.08 81.28 0)
			(effects
				(font
					(size 1.27 1.27)
				)
				(hide yes)
			)
		)
		(property "MPN" "CR0402-FX-1003GLF"
			(at 279.4 60.96 0)
			(effects
				(font
					(size 1.27 1.27)
					(thickness 0.15)
				)
				(justify left bottom)
				(hide yes)
			)
		)
		(property "Manufacturer" "Bourns"
			(at 281.94 60.96 0)
			(effects
				(font
					(size 1.27 1.27)
					(thickness 0.15)
				)
				(justify left bottom)
				(hide yes)
			)
		)
		(property "License" "Apache-2.0"
			(at 284.48 60.96 0)
			(effects
				(font
					(size 1.27 1.27)
					(thickness 0.15)
				)
				(justify left bottom)
				(hide yes)
			)
		)
		(property "Author" "Antmicro"
			(at 287.02 60.96 0)
			(effects
				(font
					(size 1.27 1.27)
					(thickness 0.15)
				)
				(justify left bottom)
				(hide yes)
			)
		)
		(property "Val" "100k"
			(at 256.54 80.01 90)
			(effects
				(font
					(size 1.27 1.27)
					(thickness 0.15)
				)
				(justify left)
			)
		)
		(property "Tolerance" "1%"
			(at 269.24 60.96 0)
			(effects
				(font
					(size 1.27 1.27)
				)
				(justify left bottom)
				(hide yes)
			)
		)
		(property "Public" "False"
			(at 289.56 60.96 0)
			(effects
				(font
					(size 1.27 1.27)
				)
				(justify left bottom)
				(hide yes)
			)
		)
		(pin "2"
		)
		(pin "1"
		)
		(instances
			(project "com-express-7-baseboard"
				(path ""
					(reference "R173")
					(unit 1)
				)
			)
		)
	)
	(symbol
		(lib_id "antmicroPMICPowerSequencers:TPS3840PL30DBVR")
		(at 236.22 102.87 0)
		(unit 1)
		(exclude_from_sim no)
		(in_bom yes)
		(on_board yes)
		(dnp no)
		(property "Reference" "U32"
			(at 245.11 96.52 0)
			(effects
				(font
					(size 1.27 1.27)
					(thickness 0.15)
				)
			)
		)
		(property "Value" "TPS3840PL30DBVR"
			(at 245.11 97.79 0)
			(effects
				(font
					(size 1.27 1.27)
					(thickness 0.15)
				)
				(hide yes)
			)
		)
		(property "Footprint" "antmicro-footprints:SOT-23-5"
			(at 274.32 109.22 0)
			(effects
				(font
					(size 1.27 1.27)
					(thickness 0.15)
				)
				(justify left bottom)
				(hide yes)
			)
		)
		(property "Datasheet" "https://www.ti.com/lit/ds/symlink/tps3840.pdf?HQS=dis-mous-null-mousermode-dsf-pf-null-wwe&DCM=yes&ref_url=https%3A%2F%2Fwww.mouser.com%2F&distId=26"
			(at 274.32 111.76 0)
			(effects
				(font
					(size 1.27 1.27)
					(thickness 0.15)
				)
				(justify left bottom)
				(hide yes)
			)
		)
		(property "Description" ""
			(at 236.22 102.87 0)
			(effects
				(font
					(size 1.27 1.27)
				)
				(hide yes)
			)
		)
		(property "Manufacturer" "Texas Instruments"
			(at 274.32 114.3 0)
			(effects
				(font
					(size 1.27 1.27)
					(thickness 0.15)
				)
				(justify left bottom)
				(hide yes)
			)
		)
		(property "MPN" "TPS3840PL30DBVR"
			(at 236.22 99.06 0)
			(effects
				(font
					(size 1.27 1.27)
					(thickness 0.15)
				)
				(justify left)
			)
		)
		(property "Author" "Antmicro"
			(at 274.32 119.38 0)
			(effects
				(font
					(size 1.27 1.27)
					(thickness 0.15)
				)
				(justify left bottom)
				(hide yes)
			)
		)
		(property "License" "Apache-2.0"
			(at 274.32 121.92 0)
			(effects
				(font
					(size 1.27 1.27)
					(thickness 0.15)
				)
				(justify left bottom)
				(hide yes)
			)
		)
		(pin "4"
		)
		(pin "5"
		)
		(pin "3"
		)
		(pin "1"
		)
		(pin "2"
		)
		(instances
			(project "com-express-7-baseboard"
				(path ""
					(reference "U32")
					(unit 1)
				)
			)
		)
	)
	(symbol
		(lib_id "antmicroResistors0402:R_1k_0402")
		(at 88.9 134.62 0)
		(unit 1)
		(exclude_from_sim no)
		(in_bom yes)
		(on_board yes)
		(dnp no)
		(property "Reference" "R160"
			(at 86.36 133.35 0)
			(effects
				(font
					(size 1.27 1.27)
					(thickness 0.15)
				)
			)
		)
		(property "Value" "R_1k_0402"
			(at 109.22 147.32 0)
			(effects
				(font
					(size 1.27 1.27)
					(thickness 0.15)
				)
				(justify left bottom)
				(hide yes)
			)
		)
		(property "Footprint" "antmicro-footprints:R_0402_1005Metric"
			(at 109.22 149.86 0)
			(effects
				(font
					(size 1.27 1.27)
					(thickness 0.15)
				)
				(justify left bottom)
				(hide yes)
			)
		)
		(property "Datasheet" "https://www.bourns.com/docs/product-datasheets/cr.pdf"
			(at 109.22 152.4 0)
			(effects
				(font
					(size 1.27 1.27)
					(thickness 0.15)
				)
				(justify left bottom)
				(hide yes)
			)
		)
		(property "Description" ""
			(at 88.9 134.62 0)
			(effects
				(font
					(size 1.27 1.27)
				)
				(hide yes)
			)
		)
		(property "MPN" "CR0402-FX-1001GLF"
			(at 109.22 154.94 0)
			(effects
				(font
					(size 1.27 1.27)
					(thickness 0.15)
				)
				(justify left bottom)
				(hide yes)
			)
		)
		(property "Manufacturer" "Bourns"
			(at 109.22 157.48 0)
			(effects
				(font
					(size 1.27 1.27)
					(thickness 0.15)
				)
				(justify left bottom)
				(hide yes)
			)
		)
		(property "License" "Apache-2.0"
			(at 109.22 160.02 0)
			(effects
				(font
					(size 1.27 1.27)
					(thickness 0.15)
				)
				(justify left bottom)
				(hide yes)
			)
		)
		(property "Author" "Antmicro"
			(at 109.22 162.56 0)
			(effects
				(font
					(size 1.27 1.27)
					(thickness 0.15)
				)
				(justify left bottom)
				(hide yes)
			)
		)
		(property "Val" "1k"
			(at 95.25 133.35 0)
			(effects
				(font
					(size 1.27 1.27)
					(thickness 0.15)
				)
			)
		)
		(property "Tolerance" "1%"
			(at 109.22 144.78 0)
			(effects
				(font
					(size 1.27 1.27)
				)
				(justify left bottom)
				(hide yes)
			)
		)
		(property "Public" "False"
			(at 109.22 165.1 0)
			(effects
				(font
					(size 1.27 1.27)
				)
				(justify left bottom)
				(hide yes)
			)
		)
		(pin "2"
		)
		(pin "1"
		)
		(instances
			(project "com-express-7-baseboard"
				(path ""
					(reference "R160")
					(unit 1)
				)
			)
		)
	)
	(symbol
		(lib_id "antmicroResistors0402:R_5k1_0402")
		(at 99.06 190.5 90)
		(unit 1)
		(exclude_from_sim no)
		(in_bom yes)
		(on_board yes)
		(dnp no)
		(property "Reference" "R163"
			(at 100.33 186.69 90)
			(effects
				(font
					(size 1.27 1.27)
					(thickness 0.15)
				)
				(justify right)
			)
		)
		(property "Value" "R_5k1_0402"
			(at 111.76 170.18 0)
			(effects
				(font
					(size 1.27 1.27)
					(thickness 0.15)
				)
				(justify left bottom)
				(hide yes)
			)
		)
		(property "Footprint" "antmicro-footprints:R_0402_1005Metric"
			(at 114.3 170.18 0)
			(effects
				(font
					(size 1.27 1.27)
					(thickness 0.15)
				)
				(justify left bottom)
				(hide yes)
			)
		)
		(property "Datasheet" "https://www.bourns.com/docs/product-datasheets/cr.pdf"
			(at 116.84 170.18 0)
			(effects
				(font
					(size 1.27 1.27)
					(thickness 0.15)
				)
				(justify left bottom)
				(hide yes)
			)
		)
		(property "Description" ""
			(at 99.06 190.5 0)
			(effects
				(font
					(size 1.27 1.27)
				)
				(hide yes)
			)
		)
		(property "MPN" "CR0402-FX-5101GLF"
			(at 119.38 170.18 0)
			(effects
				(font
					(size 1.27 1.27)
					(thickness 0.15)
				)
				(justify left bottom)
				(hide yes)
			)
		)
		(property "Manufacturer" "Bourns"
			(at 121.92 170.18 0)
			(effects
				(font
					(size 1.27 1.27)
					(thickness 0.15)
				)
				(justify left bottom)
				(hide yes)
			)
		)
		(property "License" "Apache-2.0"
			(at 124.46 170.18 0)
			(effects
				(font
					(size 1.27 1.27)
					(thickness 0.15)
				)
				(justify left bottom)
				(hide yes)
			)
		)
		(property "Author" "Antmicro"
			(at 127 170.18 0)
			(effects
				(font
					(size 1.27 1.27)
					(thickness 0.15)
				)
				(justify left bottom)
				(hide yes)
			)
		)
		(property "Val" "5k1"
			(at 100.33 189.23 90)
			(effects
				(font
					(size 1.27 1.27)
					(thickness 0.15)
				)
				(justify right)
			)
		)
		(property "Tolerance" "1%"
			(at 109.22 170.18 0)
			(effects
				(font
					(size 1.27 1.27)
				)
				(justify left bottom)
				(hide yes)
			)
		)
		(property "Public" "False"
			(at 129.54 170.18 0)
			(effects
				(font
					(size 1.27 1.27)
				)
				(justify left bottom)
				(hide yes)
			)
		)
		(pin "1"
		)
		(pin "2"
		)
		(instances
			(project "com-express-7-baseboard"
				(path ""
					(reference "R163")
					(unit 1)
				)
			)
		)
	)
	(symbol
		(lib_id "antmicroResistors0402:R_0R_0402")
		(at 304.8 63.5 0)
		(unit 1)
		(exclude_from_sim no)
		(in_bom yes)
		(on_board yes)
		(dnp no)
		(property "Reference" "R177"
			(at 302.26 64.77 0)
			(effects
				(font
					(size 1.27 1.27)
					(thickness 0.15)
				)
			)
		)
		(property "Value" "R_0R_0402"
			(at 325.12 76.2 0)
			(effects
				(font
					(size 1.27 1.27)
					(thickness 0.15)
				)
				(justify left bottom)
				(hide yes)
			)
		)
		(property "Footprint" "antmicro-footprints:R_0402_1005Metric"
			(at 325.12 78.74 0)
			(effects
				(font
					(size 1.27 1.27)
					(thickness 0.15)
				)
				(justify left bottom)
				(hide yes)
			)
		)
		(property "Datasheet" "https://industrial.panasonic.com/cdbs/www-data/pdf/RDA0000/AOA0000C301.pdf"
			(at 325.12 81.28 0)
			(effects
				(font
					(size 1.27 1.27)
					(thickness 0.15)
				)
				(justify left bottom)
				(hide yes)
			)
		)
		(property "Description" ""
			(at 304.8 63.5 0)
			(effects
				(font
					(size 1.27 1.27)
				)
				(hide yes)
			)
		)
		(property "MPN" "ERJ2GE0R00X"
			(at 325.12 83.82 0)
			(effects
				(font
					(size 1.27 1.27)
					(thickness 0.15)
				)
				(justify left bottom)
				(hide yes)
			)
		)
		(property "Manufacturer" "Panasonic"
			(at 325.12 86.36 0)
			(effects
				(font
					(size 1.27 1.27)
					(thickness 0.15)
				)
				(justify left bottom)
				(hide yes)
			)
		)
		(property "License" "Apache-2.0"
			(at 325.12 88.9 0)
			(effects
				(font
					(size 1.27 1.27)
					(thickness 0.15)
				)
				(justify left bottom)
				(hide yes)
			)
		)
		(property "Author" "Antmicro"
			(at 325.12 91.44 0)
			(effects
				(font
					(size 1.27 1.27)
					(thickness 0.15)
				)
				(justify left bottom)
				(hide yes)
			)
		)
		(property "Val" "0R"
			(at 311.15 64.77 0)
			(effects
				(font
					(size 1.27 1.27)
					(thickness 0.15)
				)
			)
		)
		(property "Tolerance" "~"
			(at 325.12 73.66 0)
			(effects
				(font
					(size 1.27 1.27)
				)
				(justify left bottom)
				(hide yes)
			)
		)
		(property "Current" "1A"
			(at 325.12 93.98 0)
			(effects
				(font
					(size 1.27 1.27)
					(thickness 0.15)
				)
				(justify left bottom)
				(hide yes)
			)
		)
		(property "Public" "False"
			(at 325.12 93.98 0)
			(effects
				(font
					(size 1.27 1.27)
				)
				(justify left bottom)
				(hide yes)
			)
		)
		(pin "2"
		)
		(pin "1"
		)
		(instances
			(project "com-express-7-baseboard"
				(path ""
					(reference "R177")
					(unit 1)
				)
			)
		)
	)
	(symbol
		(lib_id "antmicroTestPoints:TP_0.75mm_SMD")
		(at 76.2 111.76 0)
		(unit 1)
		(exclude_from_sim no)
		(in_bom no)
		(on_board yes)
		(dnp no)
		(fields_autoplaced yes)
		(property "Reference" "TP24"
			(at 81.28 111.76 0)
			(effects
				(font
					(size 1.27 1.27)
					(thickness 0.15)
				)
				(justify left)
			)
		)
		(property "Value" "TP_0.75mm_SMD"
			(at 86.995 115.57 0)
			(effects
				(font
					(size 1.27 1.27)
					(thickness 0.15)
				)
				(justify left bottom)
				(hide yes)
			)
		)
		(property "Footprint" "antmicro-footprints:TP_SMD_0.75mm"
			(at 86.995 118.11 0)
			(effects
				(font
					(size 1.27 1.27)
					(thickness 0.15)
				)
				(justify left bottom)
				(hide yes)
			)
		)
		(property "Datasheet" ""
			(at 93.98 124.46 0)
			(effects
				(font
					(size 1.27 1.27)
					(thickness 0.15)
				)
				(justify left bottom)
				(hide yes)
			)
		)
		(property "Description" ""
			(at 76.2 111.76 0)
			(effects
				(font
					(size 1.27 1.27)
				)
				(hide yes)
			)
		)
		(property "MPN" ""
			(at 86.995 123.19 0)
			(effects
				(font
					(size 1.27 1.27)
					(thickness 0.15)
				)
				(justify left bottom)
				(hide yes)
			)
		)
		(property "Manufacturer" ""
			(at 86.995 118.11 0)
			(effects
				(font
					(size 1.27 1.27)
					(thickness 0.15)
				)
				(justify left bottom)
				(hide yes)
			)
		)
		(property "Author" "Antmicro"
			(at 86.995 120.65 0)
			(effects
				(font
					(size 1.27 1.27)
					(thickness 0.15)
				)
				(justify left bottom)
				(hide yes)
			)
		)
		(property "License" "Apache-2.0"
			(at 86.995 123.19 0)
			(effects
				(font
					(size 1.27 1.27)
					(thickness 0.15)
				)
				(justify left bottom)
				(hide yes)
			)
		)
		(property "Public" "False"
			(at 86.36 125.73 0)
			(effects
				(font
					(size 1.27 1.27)
				)
				(justify left bottom)
				(hide yes)
			)
		)
		(pin "1"
		)
		(instances
			(project "com-express-7-baseboard"
				(path ""
					(reference "TP24")
					(unit 1)
				)
			)
		)
	)
	(symbol
		(lib_id "antmicroResistors0402:R_10k_0402")
		(at 302.26 58.42 90)
		(unit 1)
		(exclude_from_sim no)
		(in_bom yes)
		(on_board yes)
		(dnp no)
		(fields_autoplaced yes)
		(property "Reference" "R176"
			(at 304.8 54.61 90)
			(effects
				(font
					(size 1.27 1.27)
					(thickness 0.15)
				)
				(justify right)
			)
		)
		(property "Value" "R_10k_0402"
			(at 314.96 38.1 0)
			(effects
				(font
					(size 1.27 1.27)
					(thickness 0.15)
				)
				(justify left bottom)
				(hide yes)
			)
		)
		(property "Footprint" "antmicro-footprints:R_0402_1005Metric"
			(at 317.5 38.1 0)
			(effects
				(font
					(size 1.27 1.27)
					(thickness 0.15)
				)
				(justify left bottom)
				(hide yes)
			)
		)
		(property "Datasheet" "https://www.bourns.com/docs/product-datasheets/cr.pdf"
			(at 320.04 38.1 0)
			(effects
				(font
					(size 1.27 1.27)
					(thickness 0.15)
				)
				(justify left bottom)
				(hide yes)
			)
		)
		(property "Description" ""
			(at 302.26 58.42 0)
			(effects
				(font
					(size 1.27 1.27)
				)
				(hide yes)
			)
		)
		(property "MPN" "CR0402-FX-1002GLF"
			(at 322.58 38.1 0)
			(effects
				(font
					(size 1.27 1.27)
					(thickness 0.15)
				)
				(justify left bottom)
				(hide yes)
			)
		)
		(property "Manufacturer" "Bourns"
			(at 325.12 38.1 0)
			(effects
				(font
					(size 1.27 1.27)
					(thickness 0.15)
				)
				(justify left bottom)
				(hide yes)
			)
		)
		(property "License" "Apache-2.0"
			(at 327.66 38.1 0)
			(effects
				(font
					(size 1.27 1.27)
					(thickness 0.15)
				)
				(justify left bottom)
				(hide yes)
			)
		)
		(property "Author" "Antmicro"
			(at 330.2 38.1 0)
			(effects
				(font
					(size 1.27 1.27)
					(thickness 0.15)
				)
				(justify left bottom)
				(hide yes)
			)
		)
		(property "Val" "10k"
			(at 304.8 57.15 90)
			(effects
				(font
					(size 1.27 1.27)
					(thickness 0.15)
				)
				(justify right)
			)
		)
		(property "Tolerance" "1%"
			(at 312.42 38.1 0)
			(effects
				(font
					(size 1.27 1.27)
				)
				(justify left bottom)
				(hide yes)
			)
		)
		(property "Public" "False"
			(at 332.74 38.1 0)
			(effects
				(font
					(size 1.27 1.27)
				)
				(justify left bottom)
				(hide yes)
			)
		)
		(pin "1"
		)
		(pin "2"
		)
		(instances
			(project "com-express-7-baseboard"
				(path ""
					(reference "R176")
					(unit 1)
				)
			)
		)
	)
	(symbol
		(lib_id "antmicropower:GND")
		(at 331.47 158.75 0)
		(unit 1)
		(exclude_from_sim no)
		(in_bom yes)
		(on_board yes)
		(dnp no)
		(property "Reference" "#PWR0261"
			(at 340.36 161.29 0)
			(effects
				(font
					(size 1.27 1.27)
					(thickness 0.15)
				)
				(justify left bottom)
				(hide yes)
			)
		)
		(property "Value" "GND"
			(at 331.47 162.56 0)
			(effects
				(font
					(size 1.27 1.27)
					(thickness 0.15)
				)
			)
		)
		(property "Footprint" ""
			(at 340.36 166.37 0)
			(effects
				(font
					(size 1.27 1.27)
					(thickness 0.15)
				)
				(justify left bottom)
				(hide yes)
			)
		)
		(property "Datasheet" ""
			(at 340.36 171.45 0)
			(effects
				(font
					(size 1.27 1.27)
					(thickness 0.15)
				)
				(justify left bottom)
				(hide yes)
			)
		)
		(property "Description" ""
			(at 331.47 158.75 0)
			(effects
				(font
					(size 1.27 1.27)
				)
				(hide yes)
			)
		)
		(property "Author" "Antmicro"
			(at 340.36 166.37 0)
			(effects
				(font
					(size 1.27 1.27)
					(thickness 0.15)
				)
				(justify left bottom)
				(hide yes)
			)
		)
		(property "License" "Apache-2.0"
			(at 340.36 168.91 0)
			(effects
				(font
					(size 1.27 1.27)
					(thickness 0.15)
				)
				(justify left bottom)
				(hide yes)
			)
		)
		(pin "1"
		)
		(instances
			(project "com-express-7-baseboard"
				(path ""
					(reference "#PWR0261")
					(unit 1)
				)
			)
		)
	)
	(symbol
		(lib_id "antmicropower:+3V3_AON")
		(at 218.44 100.33 0)
		(unit 1)
		(exclude_from_sim no)
		(in_bom yes)
		(on_board yes)
		(dnp no)
		(property "Reference" "#PWR0243"
			(at 218.44 104.14 0)
			(effects
				(font
					(size 1.27 1.27)
				)
				(hide yes)
			)
		)
		(property "Value" "+3V3_AON"
			(at 218.44 96.52 0)
			(effects
				(font
					(size 1.27 1.27)
				)
			)
		)
		(property "Footprint" ""
			(at 218.44 100.33 0)
			(effects
				(font
					(size 1.27 1.27)
				)
				(hide yes)
			)
		)
		(property "Datasheet" ""
			(at 218.44 100.33 0)
			(effects
				(font
					(size 1.27 1.27)
				)
				(hide yes)
			)
		)
		(property "Description" ""
			(at 218.44 100.33 0)
			(effects
				(font
					(size 1.27 1.27)
				)
				(hide yes)
			)
		)
		(pin "1"
		)
		(instances
			(project "com-express-7-baseboard"
				(path ""
					(reference "#PWR0243")
					(unit 1)
				)
			)
		)
	)
	(symbol
		(lib_id "antmicropower:+3V3_AON")
		(at 248.92 130.81 0)
		(unit 1)
		(exclude_from_sim no)
		(in_bom yes)
		(on_board yes)
		(dnp no)
		(property "Reference" "#PWR0245"
			(at 248.92 134.62 0)
			(effects
				(font
					(size 1.27 1.27)
				)
				(hide yes)
			)
		)
		(property "Value" "+3V3_AON"
			(at 248.92 127 0)
			(effects
				(font
					(size 1.27 1.27)
				)
			)
		)
		(property "Footprint" ""
			(at 248.92 130.81 0)
			(effects
				(font
					(size 1.27 1.27)
				)
				(hide yes)
			)
		)
		(property "Datasheet" ""
			(at 248.92 130.81 0)
			(effects
				(font
					(size 1.27 1.27)
				)
				(hide yes)
			)
		)
		(property "Description" ""
			(at 248.92 130.81 0)
			(effects
				(font
					(size 1.27 1.27)
				)
				(hide yes)
			)
		)
		(pin "1"
		)
		(instances
			(project "com-express-7-baseboard"
				(path ""
					(reference "#PWR0245")
					(unit 1)
				)
			)
		)
	)
	(symbol
		(lib_id "antmicropower:PWR_FLAG")
		(at 91.44 68.58 270)
		(unit 1)
		(exclude_from_sim no)
		(in_bom yes)
		(on_board yes)
		(dnp no)
		(property "Reference" "#FLG016"
			(at 93.345 68.58 0)
			(effects
				(font
					(size 1.27 1.27)
				)
				(hide yes)
			)
		)
		(property "Value" "PWR_FLAG"
			(at 93.98 68.58 90)
			(effects
				(font
					(size 1.27 1.27)
				)
				(justify left)
			)
		)
		(property "Footprint" ""
			(at 91.44 68.58 0)
			(effects
				(font
					(size 1.27 1.27)
				)
				(hide yes)
			)
		)
		(property "Datasheet" ""
			(at 91.44 68.58 0)
			(effects
				(font
					(size 1.27 1.27)
				)
				(hide yes)
			)
		)
		(property "Description" ""
			(at 91.44 68.58 0)
			(effects
				(font
					(size 1.27 1.27)
				)
				(hide yes)
			)
		)
		(pin "1"
		)
		(instances
			(project "com-express-7-baseboard"
				(path ""
					(reference "#FLG016")
					(unit 1)
				)
			)
		)
	)
	(symbol
		(lib_id "antmicroDiodesRectifiersSingle:BAT54C")
		(at 135.89 63.5 180)
		(unit 1)
		(exclude_from_sim no)
		(in_bom yes)
		(on_board yes)
		(dnp no)
		(fields_autoplaced yes)
		(property "Reference" "D19"
			(at 129.54 52.07 0)
			(effects
				(font
					(size 1.27 1.27)
					(thickness 0.15)
				)
			)
		)
		(property "Value" "BAT54C"
			(at 113.03 54.61 0)
			(effects
				(font
					(size 1.27 1.27)
					(thickness 0.15)
				)
				(justify left bottom)
				(hide yes)
			)
		)
		(property "Footprint" "antmicro-footprints:SOT-23-3"
			(at 113.03 52.07 0)
			(effects
				(font
					(size 1.27 1.27)
					(thickness 0.15)
				)
				(justify left bottom)
				(hide yes)
			)
		)
		(property "Datasheet" "https://diotec.com/request/datasheet/bat54.pdf"
			(at 113.03 49.53 0)
			(effects
				(font
					(size 1.27 1.27)
					(thickness 0.15)
				)
				(justify left bottom)
				(hide yes)
			)
		)
		(property "Description" ""
			(at 135.89 63.5 0)
			(effects
				(font
					(size 1.27 1.27)
				)
				(hide yes)
			)
		)
		(property "MPN" "BAT54C"
			(at 129.54 54.61 0)
			(effects
				(font
					(size 1.27 1.27)
					(thickness 0.15)
				)
			)
		)
		(property "Manufacturer" "Diotec Semiconductor"
			(at 113.03 46.99 0)
			(effects
				(font
					(size 1.27 1.27)
					(thickness 0.15)
				)
				(justify left bottom)
				(hide yes)
			)
		)
		(property "Author" "Antmicro"
			(at 113.03 44.45 0)
			(effects
				(font
					(size 1.27 1.27)
					(thickness 0.15)
				)
				(justify left bottom)
				(hide yes)
			)
		)
		(property "License" "Apache-2.0"
			(at 113.03 41.91 0)
			(effects
				(font
					(size 1.27 1.27)
					(thickness 0.15)
				)
				(justify left bottom)
				(hide yes)
			)
		)
		(pin "1"
		)
		(pin "3"
		)
		(pin "2"
		)
		(instances
			(project "com-express-7-baseboard"
				(path ""
					(reference "D19")
					(unit 1)
				)
			)
		)
	)
	(symbol
		(lib_id "antmicropower:GND")
		(at 250.19 226.06 0)
		(unit 1)
		(exclude_from_sim no)
		(in_bom yes)
		(on_board yes)
		(dnp no)
		(property "Reference" "#PWR0248"
			(at 259.08 228.6 0)
			(effects
				(font
					(size 1.27 1.27)
					(thickness 0.15)
				)
				(justify left bottom)
				(hide yes)
			)
		)
		(property "Value" "GND"
			(at 250.19 229.87 0)
			(effects
				(font
					(size 1.27 1.27)
					(thickness 0.15)
				)
			)
		)
		(property "Footprint" ""
			(at 259.08 233.68 0)
			(effects
				(font
					(size 1.27 1.27)
					(thickness 0.15)
				)
				(justify left bottom)
				(hide yes)
			)
		)
		(property "Datasheet" ""
			(at 259.08 238.76 0)
			(effects
				(font
					(size 1.27 1.27)
					(thickness 0.15)
				)
				(justify left bottom)
				(hide yes)
			)
		)
		(property "Description" ""
			(at 250.19 226.06 0)
			(effects
				(font
					(size 1.27 1.27)
				)
				(hide yes)
			)
		)
		(property "Author" "Antmicro"
			(at 259.08 233.68 0)
			(effects
				(font
					(size 1.27 1.27)
					(thickness 0.15)
				)
				(justify left bottom)
				(hide yes)
			)
		)
		(property "License" "Apache-2.0"
			(at 259.08 236.22 0)
			(effects
				(font
					(size 1.27 1.27)
					(thickness 0.15)
				)
				(justify left bottom)
				(hide yes)
			)
		)
		(pin "1"
		)
		(instances
			(project "com-express-7-baseboard"
				(path ""
					(reference "#PWR0248")
					(unit 1)
				)
			)
		)
	)
	(symbol
		(lib_id "antmicroTestPoints:TP_0.75mm_SMD")
		(at 76.2 167.64 0)
		(unit 1)
		(exclude_from_sim no)
		(in_bom no)
		(on_board yes)
		(dnp no)
		(fields_autoplaced yes)
		(property "Reference" "TP35"
			(at 81.28 167.64 0)
			(effects
				(font
					(size 1.27 1.27)
					(thickness 0.15)
				)
				(justify left)
			)
		)
		(property "Value" "TP_0.75mm_SMD"
			(at 86.995 171.45 0)
			(effects
				(font
					(size 1.27 1.27)
					(thickness 0.15)
				)
				(justify left bottom)
				(hide yes)
			)
		)
		(property "Footprint" "antmicro-footprints:TP_SMD_0.75mm"
			(at 86.995 173.99 0)
			(effects
				(font
					(size 1.27 1.27)
					(thickness 0.15)
				)
				(justify left bottom)
				(hide yes)
			)
		)
		(property "Datasheet" ""
			(at 93.98 180.34 0)
			(effects
				(font
					(size 1.27 1.27)
					(thickness 0.15)
				)
				(justify left bottom)
				(hide yes)
			)
		)
		(property "Description" ""
			(at 76.2 167.64 0)
			(effects
				(font
					(size 1.27 1.27)
				)
				(hide yes)
			)
		)
		(property "MPN" ""
			(at 86.995 179.07 0)
			(effects
				(font
					(size 1.27 1.27)
					(thickness 0.15)
				)
				(justify left bottom)
				(hide yes)
			)
		)
		(property "Manufacturer" ""
			(at 86.995 173.99 0)
			(effects
				(font
					(size 1.27 1.27)
					(thickness 0.15)
				)
				(justify left bottom)
				(hide yes)
			)
		)
		(property "Author" "Antmicro"
			(at 86.995 176.53 0)
			(effects
				(font
					(size 1.27 1.27)
					(thickness 0.15)
				)
				(justify left bottom)
				(hide yes)
			)
		)
		(property "License" "Apache-2.0"
			(at 86.995 179.07 0)
			(effects
				(font
					(size 1.27 1.27)
					(thickness 0.15)
				)
				(justify left bottom)
				(hide yes)
			)
		)
		(property "Public" "False"
			(at 86.36 181.61 0)
			(effects
				(font
					(size 1.27 1.27)
				)
				(justify left bottom)
				(hide yes)
			)
		)
		(pin "1"
		)
		(instances
			(project "com-express-7-baseboard"
				(path ""
					(reference "TP35")
					(unit 1)
				)
			)
		)
	)
	(symbol
		(lib_id "antmicroCapacitors0402:C_1u_25V_0402")
		(at 264.16 81.28 90)
		(unit 1)
		(exclude_from_sim no)
		(in_bom yes)
		(on_board yes)
		(dnp no)
		(fields_autoplaced yes)
		(property "Reference" "C101"
			(at 266.7 77.4636 90)
			(effects
				(font
					(size 1.27 1.27)
					(thickness 0.15)
				)
				(justify right)
			)
		)
		(property "Value" "C_1u_25V_0402"
			(at 274.32 60.96 0)
			(effects
				(font
					(size 1.27 1.27)
					(thickness 0.15)
				)
				(justify left bottom)
				(hide yes)
			)
		)
		(property "Footprint" "antmicro-footprints:C_0402_1005Metric"
			(at 276.86 60.96 0)
			(effects
				(font
					(size 1.27 1.27)
					(thickness 0.15)
				)
				(justify left bottom)
				(hide yes)
			)
		)
		(property "Datasheet" "https://www.murata.com/products/productdetail?partno=GRM155R61E105KE11%23"
			(at 279.4 60.96 0)
			(effects
				(font
					(size 1.27 1.27)
					(thickness 0.15)
				)
				(justify left bottom)
				(hide yes)
			)
		)
		(property "Description" "SMD Multilayer Ceramic Capacitor, 1 µF, 25 V, 0402 [1005 Metric], ± 10%, X5R, GRM Series"
			(at 264.16 81.28 0)
			(effects
				(font
					(size 1.27 1.27)
				)
				(hide yes)
			)
		)
		(property "MPN" "GRM155R61E105KE11J"
			(at 281.94 60.96 0)
			(effects
				(font
					(size 1.27 1.27)
					(thickness 0.15)
				)
				(justify left bottom)
				(hide yes)
			)
		)
		(property "Manufacturer" "Murata"
			(at 284.48 60.96 0)
			(effects
				(font
					(size 1.27 1.27)
					(thickness 0.15)
				)
				(justify left bottom)
				(hide yes)
			)
		)
		(property "License" "Apache-2.0"
			(at 287.02 60.96 0)
			(effects
				(font
					(size 1.27 1.27)
					(thickness 0.15)
				)
				(justify left bottom)
				(hide yes)
			)
		)
		(property "Author" "Antmicro"
			(at 289.56 60.96 0)
			(effects
				(font
					(size 1.27 1.27)
					(thickness 0.15)
				)
				(justify left bottom)
				(hide yes)
			)
		)
		(property "Val" "1u"
			(at 266.7 80.0036 90)
			(effects
				(font
					(size 1.27 1.27)
					(thickness 0.15)
				)
				(justify right)
			)
		)
		(property "Voltage" "25V"
			(at 292.1 60.96 0)
			(effects
				(font
					(size 1.27 1.27)
				)
				(justify left bottom)
				(hide yes)
			)
		)
		(property "Dielectric" "X5R"
			(at 294.64 60.96 0)
			(effects
				(font
					(size 1.27 1.27)
				)
				(justify left bottom)
				(hide yes)
			)
		)
		(pin "2"
		)
		(pin "1"
		)
		(instances
			(project ""
				(path ""
					(reference "C101")
					(unit 1)
				)
			)
		)
	)
	(symbol
		(lib_id "antmicropower:+3V3_AON")
		(at 285.75 125.73 0)
		(unit 1)
		(exclude_from_sim no)
		(in_bom yes)
		(on_board yes)
		(dnp no)
		(property "Reference" "#PWR0251"
			(at 285.75 129.54 0)
			(effects
				(font
					(size 1.27 1.27)
				)
				(hide yes)
			)
		)
		(property "Value" "+3V3_AON"
			(at 285.75 121.92 0)
			(effects
				(font
					(size 1.27 1.27)
				)
			)
		)
		(property "Footprint" ""
			(at 285.75 125.73 0)
			(effects
				(font
					(size 1.27 1.27)
				)
				(hide yes)
			)
		)
		(property "Datasheet" ""
			(at 285.75 125.73 0)
			(effects
				(font
					(size 1.27 1.27)
				)
				(hide yes)
			)
		)
		(property "Description" ""
			(at 285.75 125.73 0)
			(effects
				(font
					(size 1.27 1.27)
				)
				(hide yes)
			)
		)
		(pin "1"
		)
		(instances
			(project "com-express-7-baseboard"
				(path ""
					(reference "#PWR0251")
					(unit 1)
				)
			)
		)
	)
	(symbol
		(lib_id "antmicropower:GND")
		(at 186.69 104.14 0)
		(unit 1)
		(exclude_from_sim no)
		(in_bom yes)
		(on_board yes)
		(dnp no)
		(property "Reference" "#PWR0448"
			(at 195.58 106.68 0)
			(effects
				(font
					(size 1.27 1.27)
					(thickness 0.15)
				)
				(justify left bottom)
				(hide yes)
			)
		)
		(property "Value" "GND"
			(at 186.69 107.95 0)
			(effects
				(font
					(size 1.27 1.27)
					(thickness 0.15)
				)
			)
		)
		(property "Footprint" ""
			(at 195.58 111.76 0)
			(effects
				(font
					(size 1.27 1.27)
					(thickness 0.15)
				)
				(justify left bottom)
				(hide yes)
			)
		)
		(property "Datasheet" ""
			(at 195.58 116.84 0)
			(effects
				(font
					(size 1.27 1.27)
					(thickness 0.15)
				)
				(justify left bottom)
				(hide yes)
			)
		)
		(property "Description" ""
			(at 186.69 104.14 0)
			(effects
				(font
					(size 1.27 1.27)
				)
				(hide yes)
			)
		)
		(property "Author" "Antmicro"
			(at 195.58 111.76 0)
			(effects
				(font
					(size 1.27 1.27)
					(thickness 0.15)
				)
				(justify left bottom)
				(hide yes)
			)
		)
		(property "License" "Apache-2.0"
			(at 195.58 114.3 0)
			(effects
				(font
					(size 1.27 1.27)
					(thickness 0.15)
				)
				(justify left bottom)
				(hide yes)
			)
		)
		(pin "1"
		)
		(instances
			(project "com-express-7-baseboard"
				(path ""
					(reference "#PWR0448")
					(unit 1)
				)
			)
		)
	)
	(symbol
		(lib_id "antmicroCapacitors0402:C_100n_0402")
		(at 337.82 76.2 90)
		(unit 1)
		(exclude_from_sim no)
		(in_bom yes)
		(on_board yes)
		(dnp no)
		(fields_autoplaced yes)
		(property "Reference" "C216"
			(at 340.36 72.3836 90)
			(effects
				(font
					(size 1.27 1.27)
					(thickness 0.15)
				)
				(justify right)
			)
		)
		(property "Value" "C_100n_0402"
			(at 347.98 55.88 0)
			(effects
				(font
					(size 1.27 1.27)
					(thickness 0.15)
				)
				(justify left bottom)
				(hide yes)
			)
		)
		(property "Footprint" "antmicro-footprints:C_0402_1005Metric"
			(at 350.52 55.88 0)
			(effects
				(font
					(size 1.27 1.27)
					(thickness 0.15)
				)
				(justify left bottom)
				(hide yes)
			)
		)
		(property "Datasheet" "https://www.murata.com/products/productdetail?partno=GRM155R61H104KE14%23"
			(at 353.06 55.88 0)
			(effects
				(font
					(size 1.27 1.27)
					(thickness 0.15)
				)
				(justify left bottom)
				(hide yes)
			)
		)
		(property "Description" ""
			(at 337.82 76.2 0)
			(effects
				(font
					(size 1.27 1.27)
				)
				(hide yes)
			)
		)
		(property "MPN" "GRM155R61H104KE14D"
			(at 355.6 55.88 0)
			(effects
				(font
					(size 1.27 1.27)
					(thickness 0.15)
				)
				(justify left bottom)
				(hide yes)
			)
		)
		(property "Manufacturer" "Murata"
			(at 358.14 55.88 0)
			(effects
				(font
					(size 1.27 1.27)
					(thickness 0.15)
				)
				(justify left bottom)
				(hide yes)
			)
		)
		(property "License" "Apache-2.0"
			(at 360.68 55.88 0)
			(effects
				(font
					(size 1.27 1.27)
					(thickness 0.15)
				)
				(justify left bottom)
				(hide yes)
			)
		)
		(property "Author" "Antmicro"
			(at 363.22 55.88 0)
			(effects
				(font
					(size 1.27 1.27)
					(thickness 0.15)
				)
				(justify left bottom)
				(hide yes)
			)
		)
		(property "Val" "100n"
			(at 340.36 74.9236 90)
			(effects
				(font
					(size 1.27 1.27)
					(thickness 0.15)
				)
				(justify right)
			)
		)
		(property "Voltage" "50V"
			(at 365.76 55.88 0)
			(effects
				(font
					(size 1.27 1.27)
				)
				(justify left bottom)
				(hide yes)
			)
		)
		(property "Dielectric" "X5R"
			(at 368.3 55.88 0)
			(effects
				(font
					(size 1.27 1.27)
				)
				(justify left bottom)
				(hide yes)
			)
		)
		(property "Public" "False"
			(at 370.84 55.88 0)
			(effects
				(font
					(size 1.27 1.27)
				)
				(justify left bottom)
				(hide yes)
			)
		)
		(pin "2"
		)
		(pin "1"
		)
		(instances
			(project "com-express-7-baseboard"
				(path ""
					(reference "C216")
					(unit 1)
				)
			)
		)
	)
	(symbol
		(lib_id "antmicroB2BConnectors:Plug_Bus_CE7_EPT_401-51501-51")
		(at 76.2 106.68 0)
		(unit 4)
		(exclude_from_sim no)
		(in_bom yes)
		(on_board yes)
		(dnp no)
		(fields_autoplaced yes)
		(property "Reference" "J12"
			(at 57.15 99.06 0)
			(effects
				(font
					(size 1.27 1.27)
					(thickness 0.15)
				)
			)
		)
		(property "Value" "Plug_Bus_CE7_EPT_401-51501-51"
			(at 129.54 119.38 0)
			(effects
				(font
					(size 1.27 1.27)
					(thickness 0.15)
				)
				(justify left bottom)
				(hide yes)
			)
		)
		(property "Footprint" "antmicro-footprints:EPT_401-51501-51"
			(at 129.54 121.92 0)
			(effects
				(font
					(size 1.27 1.27)
					(thickness 0.15)
				)
				(justify left bottom)
				(hide yes)
			)
		)
		(property "Datasheet" "https://www.farnell.com/datasheets/1905093.pdf"
			(at 129.54 124.46 0)
			(effects
				(font
					(size 1.27 1.27)
					(thickness 0.15)
				)
				(justify left bottom)
				(hide yes)
			)
		)
		(property "Description" ""
			(at 76.2 106.68 0)
			(effects
				(font
					(size 1.27 1.27)
				)
				(hide yes)
			)
		)
		(property "Author" "Antmicro"
			(at 129.54 127 0)
			(effects
				(font
					(size 1.27 1.27)
					(thickness 0.15)
				)
				(justify left bottom)
				(hide yes)
			)
		)
		(property "License" "Apache-2.0"
			(at 129.54 129.54 0)
			(effects
				(font
					(size 1.27 1.27)
					(thickness 0.15)
				)
				(justify left bottom)
				(hide yes)
			)
		)
		(property "Manufacturer" "ept"
			(at 129.54 111.76 0)
			(effects
				(font
					(size 1.27 1.27)
					(thickness 0.15)
				)
				(justify left bottom)
				(hide yes)
			)
		)
		(property "MPN" "401-51501-51"
			(at 57.15 101.6 0)
			(effects
				(font
					(size 1.27 1.27)
					(thickness 0.15)
				)
			)
		)
		(pin "C91"
		)
		(pin "C92"
		)
		(pin "A15"
		)
		(pin "A91"
		)
		(pin "C34"
		)
		(pin "C35"
		)
		(pin "D22"
		)
		(pin "D23"
		)
		(pin "D55"
		)
		(pin "D56"
		)
		(pin "C55"
		)
		(pin "C56"
		)
		(pin "C71"
		)
		(pin "C72"
		)
		(pin "C32"
		)
		(pin "C33"
		)
		(pin "B6"
		)
		(pin "B58"
		)
		(pin "B59"
		)
		(pin "D5"
		)
		(pin "D51"
		)
		(pin "A29"
		)
		(pin "D46"
		)
		(pin "D47"
		)
		(pin "C105"
		)
		(pin "C106"
		)
		(pin "A16"
		)
		(pin "B22"
		)
		(pin "B51"
		)
		(pin "B30"
		)
		(pin "A44"
		)
		(pin "C51"
		)
		(pin "C60"
		)
		(pin "A81"
		)
		(pin "A82"
		)
		(pin "D90"
		)
		(pin "D93"
		)
		(pin "B68"
		)
		(pin "B69"
		)
		(pin "C103"
		)
		(pin "C104"
		)
		(pin "C58"
		)
		(pin "C59"
		)
		(pin "D84"
		)
		(pin "D87"
		)
		(pin "A30"
		)
		(pin "B29"
		)
		(pin "A41"
		)
		(pin "C40"
		)
		(pin "C42"
		)
		(pin "D80"
		)
		(pin "D83"
		)
		(pin "B103"
		)
		(pin "A102"
		)
		(pin "C101"
		)
		(pin "C102"
		)
		(pin "D11"
		)
		(pin "D110"
		)
		(pin "B37"
		)
		(pin "B45"
		)
		(pin "C61"
		)
		(pin "C62"
		)
		(pin "A42"
		)
		(pin "B36"
		)
		(pin "B57"
		)
		(pin "D12"
		)
		(pin "D44"
		)
		(pin "D48"
		)
		(pin "B32"
		)
		(pin "B107"
		)
		(pin "B108"
		)
		(pin "B110"
		)
		(pin "B101"
		)
		(pin "C63"
		)
		(pin "C64"
		)
		(pin "B50"
		)
		(pin "A87"
		)
		(pin "A86"
		)
		(pin "B27"
		)
		(pin "D17"
		)
		(pin "D24"
		)
		(pin "D26"
		)
		(pin "D27"
		)
		(pin "A47"
		)
		(pin "C81"
		)
		(pin "C82"
		)
		(pin "C68"
		)
		(pin "C69"
		)
		(pin "A74"
		)
		(pin "A48"
		)
		(pin "A57"
		)
		(pin "A43"
		)
		(pin "A31"
		)
		(pin "D29"
		)
		(pin "D30"
		)
		(pin "C36"
		)
		(pin "C37"
		)
		(pin "C3"
		)
		(pin "A35"
		)
		(pin "A34"
		)
		(pin "B7"
		)
		(pin "B46"
		)
		(pin "B1"
		)
		(pin "B63"
		)
		(pin "A51"
		)
		(pin "A99"
		)
		(pin "B17"
		)
		(pin "C13"
		)
		(pin "C4"
		)
		(pin "B102"
		)
		(pin "C38"
		)
		(pin "C39"
		)
		(pin "B3"
		)
		(pin "A90"
		)
		(pin "A72"
		)
		(pin "B84"
		)
		(pin "D19"
		)
		(pin "D20"
		)
		(pin "D43"
		)
		(pin "D45"
		)
		(pin "A77"
		)
		(pin "A78"
		)
		(pin "B38"
		)
		(pin "B86"
		)
		(pin "D77"
		)
		(pin "D8"
		)
		(pin "A32"
		)
		(pin "B85"
		)
		(pin "D73"
		)
		(pin "D76"
		)
		(pin "D63"
		)
		(pin "D64"
		)
		(pin "D67"
		)
		(pin "D70"
		)
		(pin "B83"
		)
		(pin "D81"
		)
		(pin "D82"
		)
		(pin "B41"
		)
		(pin "D49"
		)
		(pin "D50"
		)
		(pin "A75"
		)
		(pin "D2"
		)
		(pin "D21"
		)
		(pin "C78"
		)
		(pin "C79"
		)
		(pin "B19"
		)
		(pin "B39"
		)
		(pin "A12"
		)
		(pin "B66"
		)
		(pin "D4"
		)
		(pin "D85"
		)
		(pin "D86"
		)
		(pin "A105"
		)
		(pin "B90"
		)
		(pin "A22"
		)
		(pin "A109"
		)
		(pin "B88"
		)
		(pin "B14"
		)
		(pin "B71"
		)
		(pin "B52"
		)
		(pin "B53"
		)
		(pin "D7"
		)
		(pin "A108"
		)
		(pin "C85"
		)
		(pin "C86"
		)
		(pin "B61"
		)
		(pin "B62"
		)
		(pin "D68"
		)
		(pin "D69"
		)
		(pin "A88"
		)
		(pin "A89"
		)
		(pin "D6"
		)
		(pin "C7"
		)
		(pin "B33"
		)
		(pin "D88"
		)
		(pin "D89"
		)
		(pin "B26"
		)
		(pin "A76"
		)
		(pin "D101"
		)
		(pin "D102"
		)
		(pin "B12"
		)
		(pin "C15"
		)
		(pin "C16"
		)
		(pin "A18"
		)
		(pin "A13"
		)
		(pin "A66"
		)
		(pin "C26"
		)
		(pin "C27"
		)
		(pin "A101"
		)
		(pin "A17"
		)
		(pin "B96"
		)
		(pin "C22"
		)
		(pin "C23"
		)
		(pin "A79"
		)
		(pin "A54"
		)
		(pin "C41"
		)
		(pin "C44"
		)
		(pin "A100"
		)
		(pin "A67"
		)
		(pin "A10"
		)
		(pin "A14"
		)
		(pin "C6"
		)
		(pin "A84"
		)
		(pin "B91"
		)
		(pin "C29"
		)
		(pin "C30"
		)
		(pin "A37"
		)
		(pin "A39"
		)
		(pin "B10"
		)
		(pin "B34"
		)
		(pin "C54"
		)
		(pin "C57"
		)
		(pin "B64"
		)
		(pin "B65"
		)
		(pin "A58"
		)
		(pin "A59"
		)
		(pin "B92"
		)
		(pin "C43"
		)
		(pin "C45"
		)
		(pin "A97"
		)
		(pin "A11"
		)
		(pin "A61"
		)
		(pin "A62"
		)
		(pin "B48"
		)
		(pin "B54"
		)
		(pin "D71"
		)
		(pin "D72"
		)
		(pin "A26"
		)
		(pin "A36"
		)
		(pin "D31"
		)
		(pin "D36"
		)
		(pin "B76"
		)
		(pin "B21"
		)
		(pin "B24"
		)
		(pin "B94"
		)
		(pin "D3"
		)
		(pin "B79"
		)
		(pin "A85"
		)
		(pin "A23"
		)
		(pin "A25"
		)
		(pin "A24"
		)
		(pin "D14"
		)
		(pin "D18"
		)
		(pin "B15"
		)
		(pin "A107"
		)
		(pin "A98"
		)
		(pin "D9"
		)
		(pin "B44"
		)
		(pin "A4"
		)
		(pin "C28"
		)
		(pin "C31"
		)
		(pin "A9"
		)
		(pin "C49"
		)
		(pin "C50"
		)
		(pin "A83"
		)
		(pin "A110"
		)
		(pin "D52"
		)
		(pin "D53"
		)
		(pin "A40"
		)
		(pin "A71"
		)
		(pin "D98"
		)
		(pin "D99"
		)
		(pin "D40"
		)
		(pin "D42"
		)
		(pin "D37"
		)
		(pin "D41"
		)
		(pin "C109"
		)
		(pin "C11"
		)
		(pin "A106"
		)
		(pin "A3"
		)
		(pin "B109"
		)
		(pin "B40"
		)
		(pin "C70"
		)
		(pin "C73"
		)
		(pin "D13"
		)
		(pin "A1"
		)
		(pin "A46"
		)
		(pin "A20"
		)
		(pin "A104"
		)
		(pin "C9"
		)
		(pin "C110"
		)
		(pin "C14"
		)
		(pin "B23"
		)
		(pin "A93"
		)
		(pin "B89"
		)
		(pin "B87"
		)
		(pin "D54"
		)
		(pin "D60"
		)
		(pin "A21"
		)
		(pin "B93"
		)
		(pin "A70"
		)
		(pin "A60"
		)
		(pin "B97"
		)
		(pin "B95"
		)
		(pin "D38"
		)
		(pin "D39"
		)
		(pin "A50"
		)
		(pin "A52"
		)
		(pin "A53"
		)
		(pin "D91"
		)
		(pin "D92"
		)
		(pin "C67"
		)
		(pin "D57"
		)
		(pin "A96"
		)
		(pin "A92"
		)
		(pin "B70"
		)
		(pin "C46"
		)
		(pin "C47"
		)
		(pin "B4"
		)
		(pin "A64"
		)
		(pin "A65"
		)
		(pin "B43"
		)
		(pin "C21"
		)
		(pin "C25"
		)
		(pin "B42"
		)
		(pin "C19"
		)
		(pin "C20"
		)
		(pin "C18"
		)
		(pin "C2"
		)
		(pin "C107"
		)
		(pin "C108"
		)
		(pin "B35"
		)
		(pin "A28"
		)
		(pin "B11"
		)
		(pin "A103"
		)
		(pin "C97"
		)
		(pin "D1"
		)
		(pin "B98"
		)
		(pin "A19"
		)
		(pin "A68"
		)
		(pin "A69"
		)
		(pin "B55"
		)
		(pin "B56"
		)
		(pin "A8"
		)
		(pin "A33"
		)
		(pin "A95"
		)
		(pin "D96"
		)
		(pin "D97"
		)
		(pin "B31"
		)
		(pin "B105"
		)
		(pin "B100"
		)
		(pin "C65"
		)
		(pin "C66"
		)
		(pin "B104"
		)
		(pin "D61"
		)
		(pin "D62"
		)
		(pin "D78"
		)
		(pin "D79"
		)
		(pin "C83"
		)
		(pin "C84"
		)
		(pin "D74"
		)
		(pin "D75"
		)
		(pin "A45"
		)
		(pin "D106"
		)
		(pin "D107"
		)
		(pin "C8"
		)
		(pin "C80"
		)
		(pin "C87"
		)
		(pin "C90"
		)
		(pin "D58"
		)
		(pin "D59"
		)
		(pin "D104"
		)
		(pin "D105"
		)
		(pin "C93"
		)
		(pin "C96"
		)
		(pin "B73"
		)
		(pin "D108"
		)
		(pin "D109"
		)
		(pin "B20"
		)
		(pin "A27"
		)
		(pin "D34"
		)
		(pin "D35"
		)
		(pin "C17"
		)
		(pin "C24"
		)
		(pin "B49"
		)
		(pin "A6"
		)
		(pin "B5"
		)
		(pin "B99"
		)
		(pin "B25"
		)
		(pin "D94"
		)
		(pin "D95"
		)
		(pin "B106"
		)
		(pin "B67"
		)
		(pin "A2"
		)
		(pin "B13"
		)
		(pin "A49"
		)
		(pin "C52"
		)
		(pin "C53"
		)
		(pin "B72"
		)
		(pin "C94"
		)
		(pin "C95"
		)
		(pin "B74"
		)
		(pin "D10"
		)
		(pin "B75"
		)
		(pin "B77"
		)
		(pin "C98"
		)
		(pin "C99"
		)
		(pin "A7"
		)
		(pin "C88"
		)
		(pin "C89"
		)
		(pin "C10"
		)
		(pin "B78"
		)
		(pin "B81"
		)
		(pin "B28"
		)
		(pin "A63"
		)
		(pin "C76"
		)
		(pin "C77"
		)
		(pin "A55"
		)
		(pin "A56"
		)
		(pin "C48"
		)
		(pin "C5"
		)
		(pin "A5"
		)
		(pin "C1"
		)
		(pin "C100"
		)
		(pin "B47"
		)
		(pin "C74"
		)
		(pin "C75"
		)
		(pin "C12"
		)
		(pin "B80"
		)
		(pin "D15"
		)
		(pin "D16"
		)
		(pin "D100"
		)
		(pin "D103"
		)
		(pin "B2"
		)
		(pin "B9"
		)
		(pin "A94"
		)
		(pin "B82"
		)
		(pin "D25"
		)
		(pin "D28"
		)
		(pin "B16"
		)
		(pin "D65"
		)
		(pin "D66"
		)
		(pin "D32"
		)
		(pin "D33"
		)
		(pin "B8"
		)
		(pin "B60"
		)
		(pin "A38"
		)
		(pin "A73"
		)
		(pin "A80"
		)
		(pin "B18"
		)
		(pin "MP"
		)
		(instances
			(project "com-express-7-baseboard"
				(path ""
					(reference "J12")
					(unit 4)
				)
			)
		)
	)
	(symbol
		(lib_id "antmicropower:+5V_AON")
		(at 106.68 68.58 0)
		(unit 1)
		(exclude_from_sim no)
		(in_bom yes)
		(on_board yes)
		(dnp no)
		(property "Reference" "#PWR0233"
			(at 106.68 72.39 0)
			(effects
				(font
					(size 1.27 1.27)
				)
				(hide yes)
			)
		)
		(property "Value" "+5V_AON"
			(at 106.68 64.77 0)
			(effects
				(font
					(size 1.27 1.27)
				)
			)
		)
		(property "Footprint" ""
			(at 106.68 68.58 0)
			(effects
				(font
					(size 1.27 1.27)
				)
				(hide yes)
			)
		)
		(property "Datasheet" ""
			(at 106.68 68.58 0)
			(effects
				(font
					(size 1.27 1.27)
				)
				(hide yes)
			)
		)
		(property "Description" ""
			(at 106.68 68.58 0)
			(effects
				(font
					(size 1.27 1.27)
				)
				(hide yes)
			)
		)
		(pin "1"
		)
		(instances
			(project "com-express-7-baseboard"
				(path ""
					(reference "#PWR0233")
					(unit 1)
				)
			)
		)
	)
	(symbol
		(lib_id "antmicropower:+3V3_AON")
		(at 228.6 204.47 0)
		(mirror y)
		(unit 1)
		(exclude_from_sim no)
		(in_bom yes)
		(on_board yes)
		(dnp no)
		(property "Reference" "#PWR0247"
			(at 228.6 208.28 0)
			(effects
				(font
					(size 1.27 1.27)
				)
				(hide yes)
			)
		)
		(property "Value" "+3V3_AON"
			(at 228.6 200.66 0)
			(effects
				(font
					(size 1.27 1.27)
				)
			)
		)
		(property "Footprint" ""
			(at 228.6 204.47 0)
			(effects
				(font
					(size 1.27 1.27)
				)
				(hide yes)
			)
		)
		(property "Datasheet" ""
			(at 228.6 204.47 0)
			(effects
				(font
					(size 1.27 1.27)
				)
				(hide yes)
			)
		)
		(property "Description" ""
			(at 228.6 204.47 0)
			(effects
				(font
					(size 1.27 1.27)
				)
				(hide yes)
			)
		)
		(pin "1"
		)
		(instances
			(project "com-express-7-baseboard"
				(path ""
					(reference "#PWR0247")
					(unit 1)
				)
			)
		)
	)
	(symbol
		(lib_id "antmicroCapacitors0402:C_100n_0402")
		(at 317.5 74.93 90)
		(unit 1)
		(exclude_from_sim no)
		(in_bom yes)
		(on_board yes)
		(dnp yes)
		(fields_autoplaced yes)
		(property "Reference" "C207"
			(at 320.04 71.1136 90)
			(effects
				(font
					(size 1.27 1.27)
					(thickness 0.15)
				)
				(justify right)
			)
		)
		(property "Value" "C_100n_0402"
			(at 327.66 54.61 0)
			(effects
				(font
					(size 1.27 1.27)
					(thickness 0.15)
				)
				(justify left bottom)
				(hide yes)
			)
		)
		(property "Footprint" "antmicro-footprints:C_0402_1005Metric"
			(at 330.2 54.61 0)
			(effects
				(font
					(size 1.27 1.27)
					(thickness 0.15)
				)
				(justify left bottom)
				(hide yes)
			)
		)
		(property "Datasheet" "https://www.murata.com/products/productdetail?partno=GRM155R61H104KE14%23"
			(at 332.74 54.61 0)
			(effects
				(font
					(size 1.27 1.27)
					(thickness 0.15)
				)
				(justify left bottom)
				(hide yes)
			)
		)
		(property "Description" ""
			(at 317.5 74.93 0)
			(effects
				(font
					(size 1.27 1.27)
				)
				(hide yes)
			)
		)
		(property "MPN" "GRM155R61H104KE14D"
			(at 335.28 54.61 0)
			(effects
				(font
					(size 1.27 1.27)
					(thickness 0.15)
				)
				(justify left bottom)
				(hide yes)
			)
		)
		(property "Manufacturer" "Murata"
			(at 337.82 54.61 0)
			(effects
				(font
					(size 1.27 1.27)
					(thickness 0.15)
				)
				(justify left bottom)
				(hide yes)
			)
		)
		(property "License" "Apache-2.0"
			(at 340.36 54.61 0)
			(effects
				(font
					(size 1.27 1.27)
					(thickness 0.15)
				)
				(justify left bottom)
				(hide yes)
			)
		)
		(property "Author" "Antmicro"
			(at 342.9 54.61 0)
			(effects
				(font
					(size 1.27 1.27)
					(thickness 0.15)
				)
				(justify left bottom)
				(hide yes)
			)
		)
		(property "Val" "100n"
			(at 320.04 73.6536 90)
			(effects
				(font
					(size 1.27 1.27)
					(thickness 0.15)
				)
				(justify right)
			)
		)
		(property "Voltage" "50V"
			(at 345.44 54.61 0)
			(effects
				(font
					(size 1.27 1.27)
				)
				(justify left bottom)
				(hide yes)
			)
		)
		(property "Dielectric" "X5R"
			(at 347.98 54.61 0)
			(effects
				(font
					(size 1.27 1.27)
				)
				(justify left bottom)
				(hide yes)
			)
		)
		(property "Public" "False"
			(at 350.52 54.61 0)
			(effects
				(font
					(size 1.27 1.27)
				)
				(justify left bottom)
				(hide yes)
			)
		)
		(pin "2"
		)
		(pin "1"
		)
		(instances
			(project "com-express-7-baseboard"
				(path ""
					(reference "C207")
					(unit 1)
				)
			)
		)
	)
	(symbol
		(lib_id "antmicropower:GND")
		(at 264.16 118.11 0)
		(unit 1)
		(exclude_from_sim no)
		(in_bom yes)
		(on_board yes)
		(dnp no)
		(property "Reference" "#PWR0255"
			(at 273.05 120.65 0)
			(effects
				(font
					(size 1.27 1.27)
					(thickness 0.15)
				)
				(justify left bottom)
				(hide yes)
			)
		)
		(property "Value" "GND"
			(at 264.16 121.92 0)
			(effects
				(font
					(size 1.27 1.27)
					(thickness 0.15)
				)
			)
		)
		(property "Footprint" ""
			(at 273.05 125.73 0)
			(effects
				(font
					(size 1.27 1.27)
					(thickness 0.15)
				)
				(justify left bottom)
				(hide yes)
			)
		)
		(property "Datasheet" ""
			(at 273.05 130.81 0)
			(effects
				(font
					(size 1.27 1.27)
					(thickness 0.15)
				)
				(justify left bottom)
				(hide yes)
			)
		)
		(property "Description" ""
			(at 264.16 118.11 0)
			(effects
				(font
					(size 1.27 1.27)
				)
				(hide yes)
			)
		)
		(property "Author" "Antmicro"
			(at 273.05 125.73 0)
			(effects
				(font
					(size 1.27 1.27)
					(thickness 0.15)
				)
				(justify left bottom)
				(hide yes)
			)
		)
		(property "License" "Apache-2.0"
			(at 273.05 128.27 0)
			(effects
				(font
					(size 1.27 1.27)
					(thickness 0.15)
				)
				(justify left bottom)
				(hide yes)
			)
		)
		(pin "1"
		)
		(instances
			(project "com-express-7-baseboard"
				(path ""
					(reference "#PWR0255")
					(unit 1)
				)
			)
		)
	)
	(symbol
		(lib_id "antmicroTestPoints:TP_0.75mm_SMD")
		(at 76.2 116.84 0)
		(unit 1)
		(exclude_from_sim no)
		(in_bom no)
		(on_board yes)
		(dnp no)
		(fields_autoplaced yes)
		(property "Reference" "TP26"
			(at 81.28 116.84 0)
			(effects
				(font
					(size 1.27 1.27)
					(thickness 0.15)
				)
				(justify left)
			)
		)
		(property "Value" "TP_0.75mm_SMD"
			(at 86.995 120.65 0)
			(effects
				(font
					(size 1.27 1.27)
					(thickness 0.15)
				)
				(justify left bottom)
				(hide yes)
			)
		)
		(property "Footprint" "antmicro-footprints:TP_SMD_0.75mm"
			(at 86.995 123.19 0)
			(effects
				(font
					(size 1.27 1.27)
					(thickness 0.15)
				)
				(justify left bottom)
				(hide yes)
			)
		)
		(property "Datasheet" ""
			(at 93.98 129.54 0)
			(effects
				(font
					(size 1.27 1.27)
					(thickness 0.15)
				)
				(justify left bottom)
				(hide yes)
			)
		)
		(property "Description" ""
			(at 76.2 116.84 0)
			(effects
				(font
					(size 1.27 1.27)
				)
				(hide yes)
			)
		)
		(property "MPN" ""
			(at 86.995 128.27 0)
			(effects
				(font
					(size 1.27 1.27)
					(thickness 0.15)
				)
				(justify left bottom)
				(hide yes)
			)
		)
		(property "Manufacturer" ""
			(at 86.995 123.19 0)
			(effects
				(font
					(size 1.27 1.27)
					(thickness 0.15)
				)
				(justify left bottom)
				(hide yes)
			)
		)
		(property "Author" "Antmicro"
			(at 86.995 125.73 0)
			(effects
				(font
					(size 1.27 1.27)
					(thickness 0.15)
				)
				(justify left bottom)
				(hide yes)
			)
		)
		(property "License" "Apache-2.0"
			(at 86.995 128.27 0)
			(effects
				(font
					(size 1.27 1.27)
					(thickness 0.15)
				)
				(justify left bottom)
				(hide yes)
			)
		)
		(property "Public" "False"
			(at 86.36 130.81 0)
			(effects
				(font
					(size 1.27 1.27)
				)
				(justify left bottom)
				(hide yes)
			)
		)
		(pin "1"
		)
		(instances
			(project "com-express-7-baseboard"
				(path ""
					(reference "TP26")
					(unit 1)
				)
			)
		)
	)
	(symbol
		(lib_id "antmicroGenericPinHeaders:PinHeader_1x3_P2.54mm_Drill1.1mm")
		(at 88.9 59.69 90)
		(unit 1)
		(exclude_from_sim no)
		(in_bom yes)
		(on_board yes)
		(dnp no)
		(fields_autoplaced yes)
		(property "Reference" "J13"
			(at 96.52 54.6099 90)
			(effects
				(font
					(size 1.27 1.27)
					(thickness 0.15)
				)
				(justify right)
			)
		)
		(property "Value" "PinHeader_1x3_P2.54mm_Drill1.1mm"
			(at 99.06 39.37 0)
			(effects
				(font
					(size 1.27 1.27)
					(thickness 0.15)
				)
				(justify left bottom)
				(hide yes)
			)
		)
		(property "Footprint" "antmicro-footprints:PinHeader_1x3_P2.54mm_Drill1.1mm"
			(at 101.6 39.37 0)
			(effects
				(font
					(size 1.27 1.27)
					(thickness 0.15)
				)
				(justify left bottom)
				(hide yes)
			)
		)
		(property "Datasheet" "https://katalog.we-online.de/em/datasheet/6130xx11121.pdf"
			(at 104.14 39.37 0)
			(effects
				(font
					(size 1.27 1.27)
					(thickness 0.15)
				)
				(justify left bottom)
				(hide yes)
			)
		)
		(property "Description" ""
			(at 88.9 59.69 0)
			(effects
				(font
					(size 1.27 1.27)
				)
				(hide yes)
			)
		)
		(property "MPN" "61300311121"
			(at 96.52 57.1499 90)
			(effects
				(font
					(size 1.27 1.27)
					(thickness 0.15)
				)
				(justify right)
			)
		)
		(property "Manufacturer" "Würth Elektronik"
			(at 106.68 39.37 0)
			(effects
				(font
					(size 1.27 1.27)
					(thickness 0.15)
				)
				(justify left bottom)
				(hide yes)
			)
		)
		(property "Author" "Antmicro"
			(at 111.76 39.37 0)
			(effects
				(font
					(size 1.27 1.27)
					(thickness 0.15)
				)
				(justify left bottom)
				(hide yes)
			)
		)
		(property "License" "Apache-2.0"
			(at 114.3 39.37 0)
			(effects
				(font
					(size 1.27 1.27)
					(thickness 0.15)
				)
				(justify left bottom)
				(hide yes)
			)
		)
		(pin "3"
		)
		(pin "2"
		)
		(pin "1"
		)
		(instances
			(project "com-express-7-baseboard"
				(path ""
					(reference "J13")
					(unit 1)
				)
			)
		)
	)
)
